FILE_TYPE = MACRO_DRAWING;
SET COLOR_WIRE YELLOW;
SET COLOR_PROP MONO;
SET COLOR_DOT WHITE;
SET COLOR_ARC YELLOW;
SET COLOR_BODY GREEN;
SET COLOR_NOTE MONO;
SET PROP_DISPLAY VALUE;
SET PAGE_NUMBER P99;
FORCEADD PVCCIO_CPU0..1
(1900 5100);
FORCEPROP 3 LASTPIN (1900 5050) SIG_NAME PVCCIO_CPU0\g
J 0
(1910 5060);
DISPLAY 0.659574 (1910 5060);
PAINT MONO (1910 5060);
DISPLAY INVISIBLE (1910 5060);
FORCEPROP 1 LAST PATH I1
J 0
(1950 5125);
DISPLAY 0.872340 (1950 5125);
PAINT AQUA (1950 5125);
DISPLAY INVISIBLE (1950 5125);
FORCEPROP 2 LAST CDS_LIB mstr_symbols
J 0
(1900 5100);
PAINT ORANGE (1900 5100);
DISPLAY INVISIBLE (1900 5100);
FORCEPROP 1 LAST VOLTAGE 1.1V
J 0
(1855 5057);
DISPLAY 0.340426 (1855 5057);
PAINT SKYBLUE (1855 5057);
DISPLAY INVISIBLE (1855 5057);
FORCEPROP 1 LAST BODY_TYPE PLUMBING
J 0
(1855 5057);
DISPLAY 0.340426 (1855 5057);
PAINT GREEN (1855 5057);
DISPLAY INVISIBLE (1855 5057);
FORCEPROP 1 LAST HDL_POWER PVCCIO_CPU0
J 1
(1900 5150);
DISPLAY 0.872340 (1900 5150);
PAINT GREEN (1900 5150);
DISPLAY INVISIBLE (1900 5150);
FORCEADD RES..1
(1600 4300);
FORCEPROP 1 LAST LOCATION R4T10
J 0
(1300 4250);
DISPLAY 0.617021 (1300 4250);
PAINT AQUA (1300 4250);
FORCEPROP 1 LAST VALUE 20.0
J 2
(1550 4250);
DISPLAY 0.617021 (1550 4250);
PAINT SKYBLUE (1550 4250);
FORCEPROP 2 LASTPIN (1700 4300) SIG_NAME SMB_DDR_ABC_VPP_SDA
J 0
(1890 4310);
DISPLAY 0.617021 (1890 4310);
PAINT ORANGE (1890 4310);
FORCEPROP 1 LAST MATERIAL CHIP
J 0
(1800 4200);
DISPLAY 0.617021 (1800 4200);
PAINT SKYBLUE (1800 4200);
FORCEPROP 1 LASTPIN (1500 4300) $PN 1
J 0
(1512 4312);
DISPLAY 0.617021 (1512 4312);
PAINT MONO (1512 4312);
FORCEPROP 1 LASTPIN (1700 4300) $PN 2
J 0
(1662 4312);
DISPLAY 0.617021 (1662 4312);
PAINT MONO (1662 4312);
FORCEPROP 1 LAST WATTAGE 1/16W
J 2
(1775 4200);
DISPLAY 0.617021 (1775 4200);
PAINT SKYBLUE (1775 4200);
FORCEPROP 1 LAST TOLERANCE 1%
J 0
(1875 4250);
DISPLAY 0.617021 (1875 4250);
PAINT SKYBLUE (1875 4250);
FORCEPROP 1 LAST PART_NUMBER G21796-173
J 0
(1625 4150);
DISPLAY 0.617021 (1625 4150);
PAINT BLUE (1625 4150);
FORCEPROP 1 LAST PACK_TYPE 0402
J 0
(1650 4250);
DISPLAY 0.617021 (1650 4250);
PAINT SKYBLUE (1650 4250);
FORCEPROP 2 LAST ROOM MEM
J 0
(1800 4300);
DISPLAY 1.404255 (1800 4300);
PAINT ORANGE (1800 4300);
DISPLAY INVISIBLE (1800 4300);
FORCEPROP 1 LAST PATH I10
J 0
(1550 4450);
DISPLAY 0.978723 (1550 4450);
PAINT WHITE (1550 4450);
DISPLAY INVISIBLE (1550 4450);
FORCEPROP 2 LAST CDS_LOCATION R4T10
J 0
(1300 4250);
DISPLAY 0.617021 (1300 4250);
PAINT AQUA (1300 4250);
DISPLAY INVISIBLE (1300 4250);
FORCEPROP 2 LAST $SEC 1
J 0
(1550 4500);
DISPLAY 0.936170 (1550 4500);
PAINT MONO (1550 4500);
DISPLAY INVISIBLE (1550 4500);
FORCEPROP 2 LAST CDS_SEC 1
J 0
(1550 4500);
DISPLAY 1.404255 (1550 4500);
PAINT ORANGE (1550 4500);
DISPLAY INVISIBLE (1550 4500);
FORCEPROP 2 LAST CDS_LIB mstr_discrete
J 0
(1600 4300);
PAINT ORANGE (1600 4300);
DISPLAY INVISIBLE (1600 4300);
FORCEADD OFFPAGE..6
(-2400 900);
FORCEPROP 2 LAST $XR0 55 
J 0
(-2649 900);
DISPLAY 0.638298 (-2649 900);
PAINT MONO (-2649 900);
FORCEPROP 2 LAST PATH I100
J 0
(-2625 950);
DISPLAY 1.021277 (-2625 950);
PAINT ORANGE (-2625 950);
DISPLAY INVISIBLE (-2625 950);
FORCEPROP 2 LAST CDS_LIB mstr_standard
J 0
(-2400 900);
PAINT MONO (-2400 900);
DISPLAY INVISIBLE (-2400 900);
FORCEPROP 2 LAST BOM_COST SM_CONTROLLER
J 0
(-2625 950);
DISPLAY 1.617021 (-2625 950);
PAINT ORANGE (-2625 950);
DISPLAY INVISIBLE (-2625 950);
FORCEPROP 1 LAST OFFPAGE TRUE
J 0
(-2075 775);
PAINT GREEN (-2075 775);
DISPLAY INVISIBLE (-2075 775);
FORCEPROP 1 LAST COMMENT_BODY TRUE
J 0
(-2300 825);
DISPLAY 1.872340 (-2300 825);
PAINT GREEN (-2300 825);
DISPLAY INVISIBLE (-2300 825);
FORCEADD RES..2
(1275 3600);
FORCEPROP 1 LASTPIN (1275 3700) $PN 1
J 0
(1280 3662);
DISPLAY 0.617021 (1280 3662);
PAINT MONO (1280 3662);
FORCEPROP 1 LASTPIN (1275 3500) $PN 2
J 0
(1280 3510);
DISPLAY 0.617021 (1280 3510);
PAINT MONO (1280 3510);
FORCEPROP 1 LAST WATTAGE 1/16W
J 0
(1315 3575);
DISPLAY 0.617021 (1315 3575);
PAINT SKYBLUE (1315 3575);
FORCEPROP 1 LAST MATERIAL CHIP
J 0
(1315 3525);
DISPLAY 0.617021 (1315 3525);
PAINT SKYBLUE (1315 3525);
FORCEPROP 1 LAST TOLERANCE 1.0%
J 0
(1320 3625);
DISPLAY 0.617021 (1320 3625);
PAINT SKYBLUE (1320 3625);
FORCEPROP 1 LAST VALUE 665
J 0
(1320 3675);
DISPLAY 0.617021 (1320 3675);
PAINT SKYBLUE (1320 3675);
FORCEPROP 1 LAST PART_NUMBER G21796-235
J 0
(1315 3475);
DISPLAY 0.617021 (1315 3475);
PAINT BLUE (1315 3475);
FORCEPROP 1 LAST LOCATION R3R12
J 0
(1320 3725);
DISPLAY 0.617021 (1320 3725);
PAINT AQUA (1320 3725);
FORCEPROP 1 LAST PACK_TYPE 0402
J 0
(1315 3425);
DISPLAY 0.617021 (1315 3425);
PAINT SKYBLUE (1315 3425);
FORCEPROP 2 LAST ROOM MEM
J 0
(1325 3775);
PAINT MONO (1325 3775);
DISPLAY INVISIBLE (1325 3775);
FORCEPROP 1 LAST PATH I101
J 0
(1325 3775);
DISPLAY 0.978723 (1325 3775);
PAINT WHITE (1325 3775);
DISPLAY INVISIBLE (1325 3775);
FORCEPROP 2 LAST CDS_LOCATION R3R12
J 0
(1320 3725);
DISPLAY 0.617021 (1320 3725);
PAINT AQUA (1320 3725);
DISPLAY INVISIBLE (1320 3725);
FORCEPROP 2 LAST SEC 1
J 0
(1325 3825);
DISPLAY 0.936170 (1325 3825);
PAINT MONO (1325 3825);
DISPLAY INVISIBLE (1325 3825);
FORCEPROP 2 LAST SEC_TYPE 0402
J 0
(1325 3825);
DISPLAY 1.021277 (1325 3825);
PAINT ORANGE (1325 3825);
DISPLAY INVISIBLE (1325 3825);
FORCEPROP 2 LAST BOM_COST SM_CONTROLLER
J 0
(1325 3775);
PAINT MONO (1325 3775);
DISPLAY INVISIBLE (1325 3775);
FORCEPROP 2 LAST CDS_LIB mstr_discrete
J 0
(1275 3600);
PAINT ORANGE (1275 3600);
DISPLAY INVISIBLE (1275 3600);
FORCEADD PVPP_DEF..1
(925 3900);
FORCEPROP 3 LASTPIN (925 3850) SIG_NAME PVPP_DEF\g
J 0
(935 3860);
DISPLAY 0.659574 (935 3860);
PAINT MONO (935 3860);
DISPLAY INVISIBLE (935 3860);
FORCEPROP 2 LAST ROOM SMB
J 0
(925 3975);
PAINT MONO (925 3975);
DISPLAY INVISIBLE (925 3975);
FORCEPROP 1 LAST PATH I102
J 0
(975 3925);
DISPLAY 0.872340 (975 3925);
PAINT AQUA (975 3925);
DISPLAY INVISIBLE (975 3925);
FORCEPROP 2 LAST CDS_LIB mstr_symbols
J 0
(925 3900);
PAINT ORANGE (925 3900);
DISPLAY INVISIBLE (925 3900);
FORCEPROP 2 LAST BOM_COST SM_CONTROLLER
J 0
(925 4000);
DISPLAY 1.617021 (925 4000);
PAINT ORANGE (925 4000);
DISPLAY INVISIBLE (925 4000);
FORCEPROP 1 LAST VOLTAGE 2.5V
J 0
(880 3857);
DISPLAY 0.340426 (880 3857);
PAINT SKYBLUE (880 3857);
DISPLAY INVISIBLE (880 3857);
FORCEPROP 1 LAST BODY_TYPE PLUMBING
J 0
(880 3857);
DISPLAY 0.340426 (880 3857);
PAINT GREEN (880 3857);
DISPLAY INVISIBLE (880 3857);
FORCEPROP 1 LAST HDL_POWER PVPP_DEF
J 1
(925 3950);
DISPLAY 0.872340 (925 3950);
PAINT GREEN (925 3950);
DISPLAY INVISIBLE (925 3950);
FORCEADD RES..2
(925 3600);
FORCEPROP 1 LASTPIN (925 3700) $PN 1
J 0
(930 3662);
DISPLAY 0.617021 (930 3662);
PAINT MONO (930 3662);
FORCEPROP 1 LASTPIN (925 3500) $PN 2
J 0
(930 3510);
DISPLAY 0.617021 (930 3510);
PAINT MONO (930 3510);
FORCEPROP 1 LAST WATTAGE 1/16W
J 0
(965 3575);
DISPLAY 0.617021 (965 3575);
PAINT SKYBLUE (965 3575);
FORCEPROP 1 LAST MATERIAL CHIP
J 0
(965 3525);
DISPLAY 0.617021 (965 3525);
PAINT SKYBLUE (965 3525);
FORCEPROP 1 LAST PACK_TYPE 0402
J 0
(965 3425);
DISPLAY 0.617021 (965 3425);
PAINT SKYBLUE (965 3425);
FORCEPROP 1 LAST TOLERANCE 1.0%
J 0
(970 3625);
DISPLAY 0.617021 (970 3625);
PAINT SKYBLUE (970 3625);
FORCEPROP 1 LAST VALUE 665
J 0
(970 3675);
DISPLAY 0.617021 (970 3675);
PAINT SKYBLUE (970 3675);
FORCEPROP 1 LAST PART_NUMBER G21796-235
J 0
(965 3475);
DISPLAY 0.617021 (965 3475);
PAINT BLUE (965 3475);
FORCEPROP 1 LAST LOCATION R3R5
J 0
(970 3725);
DISPLAY 0.617021 (970 3725);
PAINT AQUA (970 3725);
FORCEPROP 2 LAST ROOM MEM
J 0
(975 3775);
PAINT MONO (975 3775);
DISPLAY INVISIBLE (975 3775);
FORCEPROP 1 LAST PATH I103
J 0
(975 3775);
DISPLAY 0.978723 (975 3775);
PAINT WHITE (975 3775);
DISPLAY INVISIBLE (975 3775);
FORCEPROP 2 LAST CDS_LOCATION R3R5
J 0
(970 3725);
DISPLAY 0.617021 (970 3725);
PAINT AQUA (970 3725);
DISPLAY INVISIBLE (970 3725);
FORCEPROP 2 LAST SEC 1
J 0
(975 3825);
DISPLAY 0.936170 (975 3825);
PAINT MONO (975 3825);
DISPLAY INVISIBLE (975 3825);
FORCEPROP 2 LAST SEC_TYPE 0402
J 0
(975 3825);
DISPLAY 1.021277 (975 3825);
PAINT ORANGE (975 3825);
DISPLAY INVISIBLE (975 3825);
FORCEPROP 2 LAST CDS_LIB mstr_discrete
J 0
(925 3600);
PAINT ORANGE (925 3600);
DISPLAY INVISIBLE (925 3600);
FORCEPROP 2 LAST BOM_COST SM_CONTROLLER
J 0
(975 3775);
PAINT MONO (975 3775);
DISPLAY INVISIBLE (975 3775);
FORCEADD RES..2
(1225 2450);
FORCEPROP 1 LAST TOLERANCE 1.0%
J 0
(1270 2475);
DISPLAY 0.617021 (1270 2475);
PAINT SKYBLUE (1270 2475);
FORCEPROP 1 LASTPIN (1225 2550) $PN 1
J 0
(1230 2512);
DISPLAY 0.617021 (1230 2512);
PAINT MONO (1230 2512);
FORCEPROP 1 LAST VALUE 665
J 0
(1270 2525);
DISPLAY 0.617021 (1270 2525);
PAINT SKYBLUE (1270 2525);
FORCEPROP 1 LAST MATERIAL CHIP
J 0
(1265 2375);
DISPLAY 0.617021 (1265 2375);
PAINT SKYBLUE (1265 2375);
FORCEPROP 1 LASTPIN (1225 2350) $PN 2
J 0
(1230 2360);
DISPLAY 0.617021 (1230 2360);
PAINT MONO (1230 2360);
FORCEPROP 1 LAST PACK_TYPE 0402
J 0
(1265 2275);
DISPLAY 0.617021 (1265 2275);
PAINT SKYBLUE (1265 2275);
FORCEPROP 1 LAST LOCATION R6U18
J 0
(1270 2575);
DISPLAY 0.617021 (1270 2575);
PAINT AQUA (1270 2575);
FORCEPROP 1 LAST WATTAGE 1/16W
J 0
(1265 2425);
DISPLAY 0.617021 (1265 2425);
PAINT SKYBLUE (1265 2425);
FORCEPROP 1 LAST PART_NUMBER G21796-235
J 0
(1265 2325);
DISPLAY 0.617021 (1265 2325);
PAINT BLUE (1265 2325);
FORCEPROP 2 LAST ROOM MEM
J 0
(1275 2625);
PAINT MONO (1275 2625);
DISPLAY INVISIBLE (1275 2625);
FORCEPROP 1 LAST PATH I104
J 0
(1275 2625);
DISPLAY 0.978723 (1275 2625);
PAINT WHITE (1275 2625);
DISPLAY INVISIBLE (1275 2625);
FORCEPROP 2 LAST CDS_LOCATION R6U18
J 0
(1270 2575);
DISPLAY 0.617021 (1270 2575);
PAINT AQUA (1270 2575);
DISPLAY INVISIBLE (1270 2575);
FORCEPROP 2 LAST SEC 1
J 0
(1275 2675);
DISPLAY 0.936170 (1275 2675);
PAINT MONO (1275 2675);
DISPLAY INVISIBLE (1275 2675);
FORCEPROP 2 LAST SEC_TYPE 0402
J 0
(1275 2675);
DISPLAY 1.021277 (1275 2675);
PAINT ORANGE (1275 2675);
DISPLAY INVISIBLE (1275 2675);
FORCEPROP 2 LAST BOM_COST SM_CONTROLLER
J 0
(1275 2625);
PAINT MONO (1275 2625);
DISPLAY INVISIBLE (1275 2625);
FORCEPROP 2 LAST CDS_LIB mstr_discrete
J 0
(1225 2450);
PAINT ORANGE (1225 2450);
DISPLAY INVISIBLE (1225 2450);
FORCEADD PVPP_GHJ..1
(875 2750);
FORCEPROP 3 LASTPIN (875 2700) SIG_NAME PVPP_GHJ\g
J 0
(885 2710);
DISPLAY 0.659574 (885 2710);
PAINT MONO (885 2710);
DISPLAY INVISIBLE (885 2710);
FORCEPROP 2 LAST ROOM SMB
J 0
(875 2825);
PAINT MONO (875 2825);
DISPLAY INVISIBLE (875 2825);
FORCEPROP 1 LAST PATH I105
J 0
(925 2775);
DISPLAY 0.872340 (925 2775);
PAINT AQUA (925 2775);
DISPLAY INVISIBLE (925 2775);
FORCEPROP 2 LAST CDS_LIB mstr_symbols
J 0
(875 2750);
PAINT ORANGE (875 2750);
DISPLAY INVISIBLE (875 2750);
FORCEPROP 2 LAST BOM_COST SM_CONTROLLER
J 0
(875 2850);
DISPLAY 1.617021 (875 2850);
PAINT ORANGE (875 2850);
DISPLAY INVISIBLE (875 2850);
FORCEPROP 1 LAST VOLTAGE 2.5V
J 0
(830 2707);
DISPLAY 0.340426 (830 2707);
PAINT SKYBLUE (830 2707);
DISPLAY INVISIBLE (830 2707);
FORCEPROP 1 LAST BODY_TYPE PLUMBING
J 0
(830 2707);
DISPLAY 0.340426 (830 2707);
PAINT GREEN (830 2707);
DISPLAY INVISIBLE (830 2707);
FORCEPROP 1 LAST HDL_POWER PVPP_GHJ
J 1
(875 2800);
DISPLAY 0.872340 (875 2800);
PAINT GREEN (875 2800);
DISPLAY INVISIBLE (875 2800);
FORCEADD RES..2
(875 2450);
FORCEPROP 1 LASTPIN (875 2550) $PN 1
J 0
(880 2512);
DISPLAY 0.617021 (880 2512);
PAINT MONO (880 2512);
FORCEPROP 1 LASTPIN (875 2350) $PN 2
J 0
(880 2360);
DISPLAY 0.617021 (880 2360);
PAINT MONO (880 2360);
FORCEPROP 1 LAST WATTAGE 1/16W
J 0
(915 2425);
DISPLAY 0.617021 (915 2425);
PAINT SKYBLUE (915 2425);
FORCEPROP 1 LAST PART_NUMBER G21796-235
J 0
(915 2325);
DISPLAY 0.617021 (915 2325);
PAINT BLUE (915 2325);
FORCEPROP 1 LAST MATERIAL CHIP
J 0
(915 2375);
DISPLAY 0.617021 (915 2375);
PAINT SKYBLUE (915 2375);
FORCEPROP 1 LAST LOCATION R6U17
J 0
(920 2575);
DISPLAY 0.617021 (920 2575);
PAINT AQUA (920 2575);
FORCEPROP 1 LAST VALUE 665
J 0
(920 2525);
DISPLAY 0.617021 (920 2525);
PAINT SKYBLUE (920 2525);
FORCEPROP 1 LAST TOLERANCE 1.0%
J 0
(920 2475);
DISPLAY 0.617021 (920 2475);
PAINT SKYBLUE (920 2475);
FORCEPROP 1 LAST PACK_TYPE 0402
J 0
(915 2275);
DISPLAY 0.617021 (915 2275);
PAINT SKYBLUE (915 2275);
FORCEPROP 2 LAST ROOM MEM
J 0
(925 2625);
PAINT MONO (925 2625);
DISPLAY INVISIBLE (925 2625);
FORCEPROP 1 LAST PATH I106
J 0
(925 2625);
DISPLAY 0.978723 (925 2625);
PAINT WHITE (925 2625);
DISPLAY INVISIBLE (925 2625);
FORCEPROP 2 LAST CDS_LOCATION R6U17
J 0
(920 2575);
DISPLAY 0.617021 (920 2575);
PAINT AQUA (920 2575);
DISPLAY INVISIBLE (920 2575);
FORCEPROP 2 LAST SEC 1
J 0
(925 2675);
DISPLAY 0.936170 (925 2675);
PAINT MONO (925 2675);
DISPLAY INVISIBLE (925 2675);
FORCEPROP 2 LAST SEC_TYPE 0402
J 0
(925 2675);
DISPLAY 1.021277 (925 2675);
PAINT ORANGE (925 2675);
DISPLAY INVISIBLE (925 2675);
FORCEPROP 2 LAST CDS_LIB mstr_discrete
J 0
(875 2450);
PAINT ORANGE (875 2450);
DISPLAY INVISIBLE (875 2450);
FORCEPROP 2 LAST BOM_COST SM_CONTROLLER
J 0
(925 2625);
PAINT MONO (925 2625);
DISPLAY INVISIBLE (925 2625);
FORCEADD RES..2
(1225 1250);
FORCEPROP 1 LASTPIN (1225 1350) $PN 1
J 0
(1230 1312);
DISPLAY 0.617021 (1230 1312);
PAINT MONO (1230 1312);
FORCEPROP 1 LASTPIN (1225 1150) $PN 2
J 0
(1230 1160);
DISPLAY 0.617021 (1230 1160);
PAINT MONO (1230 1160);
FORCEPROP 1 LAST WATTAGE 1/16W
J 0
(1265 1225);
DISPLAY 0.617021 (1265 1225);
PAINT SKYBLUE (1265 1225);
FORCEPROP 1 LAST MATERIAL CHIP
J 0
(1265 1175);
DISPLAY 0.617021 (1265 1175);
PAINT SKYBLUE (1265 1175);
FORCEPROP 1 LAST PACK_TYPE 0402
J 0
(1265 1075);
DISPLAY 0.617021 (1265 1075);
PAINT SKYBLUE (1265 1075);
FORCEPROP 1 LAST VALUE 665
J 0
(1270 1325);
DISPLAY 0.617021 (1270 1325);
PAINT SKYBLUE (1270 1325);
FORCEPROP 1 LAST LOCATION R7M6
J 0
(1270 1375);
DISPLAY 0.617021 (1270 1375);
PAINT AQUA (1270 1375);
FORCEPROP 1 LAST TOLERANCE 1.0%
J 0
(1270 1275);
DISPLAY 0.617021 (1270 1275);
PAINT SKYBLUE (1270 1275);
FORCEPROP 1 LAST PART_NUMBER G21796-235
J 0
(1265 1125);
DISPLAY 0.617021 (1265 1125);
PAINT BLUE (1265 1125);
FORCEPROP 2 LAST ROOM MEM
J 0
(1275 1425);
PAINT MONO (1275 1425);
DISPLAY INVISIBLE (1275 1425);
FORCEPROP 1 LAST PATH I107
J 0
(1275 1425);
DISPLAY 0.978723 (1275 1425);
PAINT WHITE (1275 1425);
DISPLAY INVISIBLE (1275 1425);
FORCEPROP 2 LAST CDS_LOCATION R7M6
J 0
(1270 1375);
DISPLAY 0.617021 (1270 1375);
PAINT AQUA (1270 1375);
DISPLAY INVISIBLE (1270 1375);
FORCEPROP 2 LAST SEC 1
J 0
(1275 1475);
DISPLAY 0.936170 (1275 1475);
PAINT MONO (1275 1475);
DISPLAY INVISIBLE (1275 1475);
FORCEPROP 2 LAST SEC_TYPE 0402
J 0
(1275 1475);
DISPLAY 1.021277 (1275 1475);
PAINT ORANGE (1275 1475);
DISPLAY INVISIBLE (1275 1475);
FORCEPROP 2 LAST BOM_COST SM_CONTROLLER
J 0
(1275 1425);
PAINT MONO (1275 1425);
DISPLAY INVISIBLE (1275 1425);
FORCEPROP 2 LAST CDS_LIB mstr_discrete
J 0
(1225 1250);
PAINT ORANGE (1225 1250);
DISPLAY INVISIBLE (1225 1250);
FORCEADD PVPP_KLM..1
(875 1550);
FORCEPROP 3 LASTPIN (875 1500) SIG_NAME PVPP_KLM\g
J 0
(885 1510);
DISPLAY 0.659574 (885 1510);
PAINT MONO (885 1510);
DISPLAY INVISIBLE (885 1510);
FORCEPROP 2 LAST ROOM SMB
J 0
(875 1625);
PAINT MONO (875 1625);
DISPLAY INVISIBLE (875 1625);
FORCEPROP 1 LAST PATH I108
J 0
(925 1575);
DISPLAY 0.872340 (925 1575);
PAINT AQUA (925 1575);
DISPLAY INVISIBLE (925 1575);
FORCEPROP 2 LAST CDS_LIB mstr_symbols
J 0
(875 1550);
PAINT ORANGE (875 1550);
DISPLAY INVISIBLE (875 1550);
FORCEPROP 2 LAST BOM_COST SM_CONTROLLER
J 0
(875 1650);
DISPLAY 1.617021 (875 1650);
PAINT ORANGE (875 1650);
DISPLAY INVISIBLE (875 1650);
FORCEPROP 1 LAST VOLTAGE 2.5V
J 0
(830 1507);
DISPLAY 0.340426 (830 1507);
PAINT SKYBLUE (830 1507);
DISPLAY INVISIBLE (830 1507);
FORCEPROP 1 LAST BODY_TYPE PLUMBING
J 0
(830 1507);
DISPLAY 0.340426 (830 1507);
PAINT GREEN (830 1507);
DISPLAY INVISIBLE (830 1507);
FORCEPROP 1 LAST HDL_POWER PVPP_KLM
J 1
(875 1600);
DISPLAY 0.872340 (875 1600);
PAINT GREEN (875 1600);
DISPLAY INVISIBLE (875 1600);
FORCEADD RES..2
(875 1250);
FORCEPROP 1 LASTPIN (875 1350) $PN 1
J 0
(880 1312);
DISPLAY 0.617021 (880 1312);
PAINT MONO (880 1312);
FORCEPROP 1 LASTPIN (875 1150) $PN 2
J 0
(880 1160);
DISPLAY 0.617021 (880 1160);
PAINT MONO (880 1160);
FORCEPROP 1 LAST WATTAGE 1/16W
J 0
(915 1225);
DISPLAY 0.617021 (915 1225);
PAINT SKYBLUE (915 1225);
FORCEPROP 1 LAST MATERIAL CHIP
J 0
(915 1175);
DISPLAY 0.617021 (915 1175);
PAINT SKYBLUE (915 1175);
FORCEPROP 1 LAST PACK_TYPE 0402
J 0
(915 1075);
DISPLAY 0.617021 (915 1075);
PAINT SKYBLUE (915 1075);
FORCEPROP 1 LAST TOLERANCE 1.0%
J 0
(920 1275);
DISPLAY 0.617021 (920 1275);
PAINT SKYBLUE (920 1275);
FORCEPROP 1 LAST VALUE 665
J 0
(920 1325);
DISPLAY 0.617021 (920 1325);
PAINT SKYBLUE (920 1325);
FORCEPROP 1 LAST PART_NUMBER G21796-235
J 0
(915 1125);
DISPLAY 0.617021 (915 1125);
PAINT BLUE (915 1125);
FORCEPROP 1 LAST LOCATION R7M1
J 0
(920 1375);
DISPLAY 0.617021 (920 1375);
PAINT AQUA (920 1375);
FORCEPROP 2 LAST ROOM MEM
J 0
(925 1425);
PAINT MONO (925 1425);
DISPLAY INVISIBLE (925 1425);
FORCEPROP 1 LAST PATH I109
J 0
(925 1425);
DISPLAY 0.978723 (925 1425);
PAINT WHITE (925 1425);
DISPLAY INVISIBLE (925 1425);
FORCEPROP 2 LAST CDS_LOCATION R7M1
J 0
(920 1375);
DISPLAY 0.617021 (920 1375);
PAINT AQUA (920 1375);
DISPLAY INVISIBLE (920 1375);
FORCEPROP 2 LAST SEC 1
J 0
(925 1475);
DISPLAY 0.936170 (925 1475);
PAINT MONO (925 1475);
DISPLAY INVISIBLE (925 1475);
FORCEPROP 2 LAST SEC_TYPE 0402
J 0
(925 1475);
DISPLAY 1.021277 (925 1475);
PAINT ORANGE (925 1475);
DISPLAY INVISIBLE (925 1475);
FORCEPROP 2 LAST CDS_LIB mstr_discrete
J 0
(875 1250);
PAINT ORANGE (875 1250);
DISPLAY INVISIBLE (875 1250);
FORCEPROP 2 LAST BOM_COST SM_CONTROLLER
J 0
(925 1425);
PAINT MONO (925 1425);
DISPLAY INVISIBLE (925 1425);
FORCEADD RES..2
(1225 4650);
FORCEPROP 1 LASTPIN (1225 4750) $PN 1
J 0
(1230 4712);
DISPLAY 0.617021 (1230 4712);
PAINT MONO (1230 4712);
FORCEPROP 1 LAST VALUE 665
J 0
(1270 4725);
DISPLAY 0.617021 (1270 4725);
PAINT SKYBLUE (1270 4725);
FORCEPROP 1 LAST LOCATION R4T8
J 0
(1270 4775);
DISPLAY 0.617021 (1270 4775);
PAINT AQUA (1270 4775);
FORCEPROP 1 LAST TOLERANCE 1.0%
J 0
(1270 4675);
DISPLAY 0.617021 (1270 4675);
PAINT SKYBLUE (1270 4675);
FORCEPROP 1 LAST WATTAGE 1/16W
J 0
(1265 4625);
DISPLAY 0.617021 (1265 4625);
PAINT SKYBLUE (1265 4625);
FORCEPROP 1 LAST PART_NUMBER G21796-235
J 0
(1265 4525);
DISPLAY 0.617021 (1265 4525);
PAINT BLUE (1265 4525);
FORCEPROP 1 LAST MATERIAL CHIP
J 0
(1265 4575);
DISPLAY 0.617021 (1265 4575);
PAINT SKYBLUE (1265 4575);
FORCEPROP 1 LAST PACK_TYPE 0402
J 0
(1265 4475);
DISPLAY 0.617021 (1265 4475);
PAINT SKYBLUE (1265 4475);
FORCEPROP 1 LASTPIN (1225 4550) $PN 2
J 0
(1230 4560);
DISPLAY 0.617021 (1230 4560);
PAINT MONO (1230 4560);
FORCEPROP 2 LAST ROOM MEM
J 0
(1275 4825);
PAINT MONO (1275 4825);
DISPLAY INVISIBLE (1275 4825);
FORCEPROP 1 LAST PATH I11
J 0
(1275 4825);
DISPLAY 0.978723 (1275 4825);
PAINT WHITE (1275 4825);
DISPLAY INVISIBLE (1275 4825);
FORCEPROP 2 LAST CDS_LOCATION R4T8
J 0
(1270 4775);
DISPLAY 0.617021 (1270 4775);
PAINT AQUA (1270 4775);
DISPLAY INVISIBLE (1270 4775);
FORCEPROP 2 LAST SEC 1
J 0
(1275 4875);
DISPLAY 0.936170 (1275 4875);
PAINT MONO (1275 4875);
DISPLAY INVISIBLE (1275 4875);
FORCEPROP 2 LAST SEC_TYPE 0402
J 0
(1275 4875);
DISPLAY 1.021277 (1275 4875);
PAINT ORANGE (1275 4875);
DISPLAY INVISIBLE (1275 4875);
FORCEPROP 2 LAST CDS_LIB mstr_discrete
J 0
(1225 4650);
PAINT ORANGE (1225 4650);
DISPLAY INVISIBLE (1225 4650);
FORCEPROP 2 LAST BOM_COST SM_CONTROLLER
J 0
(1275 4825);
PAINT MONO (1275 4825);
DISPLAY INVISIBLE (1275 4825);
FORCEADD RES..1
(-1175 3250);
FORCEPROP 1 LAST LOCATION R3R14
J 0
(-1600 3200);
DISPLAY 0.617021 (-1600 3200);
PAINT AQUA (-1600 3200);
FORCEPROP 1 LAST VALUE 10.0
J 2
(-1375 3200);
DISPLAY 0.617021 (-1375 3200);
PAINT SKYBLUE (-1375 3200);
FORCEPROP 1 LASTPIN (-1275 3250) $PN 1
J 0
(-1263 3262);
DISPLAY 0.617021 (-1263 3262);
PAINT MONO (-1263 3262);
FORCEPROP 1 LASTPIN (-1075 3250) $PN 2
J 0
(-1113 3262);
DISPLAY 0.617021 (-1113 3262);
PAINT MONO (-1113 3262);
FORCEPROP 1 LAST TOLERANCE 1%
J 0
(-1350 3200);
DISPLAY 0.617021 (-1350 3200);
PAINT SKYBLUE (-1350 3200);
FORCEPROP 1 LAST PACK_TYPE 0402
J 0
(-575 3200);
DISPLAY 0.617021 (-575 3200);
PAINT SKYBLUE (-575 3200);
FORCEPROP 1 LAST MATERIAL CHIP
J 0
(-725 3200);
DISPLAY 0.617021 (-725 3200);
PAINT SKYBLUE (-725 3200);
FORCEPROP 1 LAST WATTAGE 1/16W
J 2
(-1125 3200);
DISPLAY 0.617021 (-1125 3200);
PAINT SKYBLUE (-1125 3200);
FORCEPROP 1 LAST PART_NUMBER G21796-066
J 0
(-1025 3200);
DISPLAY 0.617021 (-1025 3200);
PAINT BLUE (-1025 3200);
FORCEPROP 2 LAST ROOM MEM
J 0
(-1225 3350);
PAINT MONO (-1225 3350);
DISPLAY INVISIBLE (-1225 3350);
FORCEPROP 1 LAST PATH I110
J 0
(-1225 3400);
DISPLAY 0.978723 (-1225 3400);
PAINT WHITE (-1225 3400);
DISPLAY INVISIBLE (-1225 3400);
FORCEPROP 2 LAST CDS_LOCATION R3R14
J 0
(-1275 3300);
DISPLAY 0.617021 (-1275 3300);
PAINT AQUA (-1275 3300);
DISPLAY INVISIBLE (-1275 3300);
FORCEPROP 2 LAST $SEC 1
J 0
(-1225 3450);
DISPLAY 0.936170 (-1225 3450);
PAINT MONO (-1225 3450);
DISPLAY INVISIBLE (-1225 3450);
FORCEPROP 2 LAST CDS_SEC 1
J 0
(-1225 3450);
DISPLAY 1.404255 (-1225 3450);
PAINT ORANGE (-1225 3450);
DISPLAY INVISIBLE (-1225 3450);
FORCEPROP 2 LAST BOM_COST SM_CONTROLLER
J 0
(-1225 3350);
PAINT MONO (-1225 3350);
DISPLAY INVISIBLE (-1225 3350);
FORCEPROP 2 LAST CDS_LIB mstr_discrete
J 0
(-1175 3250);
PAINT MONO (-1175 3250);
DISPLAY INVISIBLE (-1175 3250);
FORCEADD RES..1
(-1100 2100);
FORCEPROP 1 LAST PACK_TYPE 0402
J 0
(-650 2050);
DISPLAY 0.617021 (-650 2050);
PAINT SKYBLUE (-650 2050);
FORCEPROP 1 LAST PART_NUMBER G21796-066
J 0
(-950 2050);
DISPLAY 0.617021 (-950 2050);
PAINT BLUE (-950 2050);
FORCEPROP 1 LAST VALUE 10.0
J 2
(-1425 2050);
DISPLAY 0.617021 (-1425 2050);
PAINT SKYBLUE (-1425 2050);
FORCEPROP 1 LAST LOCATION R6T4
J 0
(-1650 2050);
DISPLAY 0.617021 (-1650 2050);
PAINT AQUA (-1650 2050);
FORCEPROP 1 LAST TOLERANCE 1%
J 0
(-1375 2050);
DISPLAY 0.617021 (-1375 2050);
PAINT SKYBLUE (-1375 2050);
FORCEPROP 1 LAST WATTAGE 1/16W
J 2
(-1150 2050);
DISPLAY 0.617021 (-1150 2050);
PAINT SKYBLUE (-1150 2050);
FORCEPROP 1 LAST MATERIAL CHIP
J 0
(-1100 2050);
DISPLAY 0.617021 (-1100 2050);
PAINT SKYBLUE (-1100 2050);
FORCEPROP 1 LASTPIN (-1200 2100) $PN 1
J 0
(-1188 2112);
DISPLAY 0.617021 (-1188 2112);
PAINT MONO (-1188 2112);
FORCEPROP 1 LASTPIN (-1000 2100) $PN 2
J 0
(-1038 2112);
DISPLAY 0.617021 (-1038 2112);
PAINT MONO (-1038 2112);
FORCEPROP 2 LAST ROOM MEM
J 0
(-1150 2200);
PAINT MONO (-1150 2200);
DISPLAY INVISIBLE (-1150 2200);
FORCEPROP 1 LAST PATH I111
J 0
(-1150 2250);
DISPLAY 0.978723 (-1150 2250);
PAINT WHITE (-1150 2250);
DISPLAY INVISIBLE (-1150 2250);
FORCEPROP 2 LAST CDS_LOCATION R6T4
J 0
(-1200 2150);
DISPLAY 0.617021 (-1200 2150);
PAINT AQUA (-1200 2150);
DISPLAY INVISIBLE (-1200 2150);
FORCEPROP 2 LAST $SEC 1
J 0
(-1150 2300);
DISPLAY 0.936170 (-1150 2300);
PAINT MONO (-1150 2300);
DISPLAY INVISIBLE (-1150 2300);
FORCEPROP 2 LAST CDS_SEC 1
J 0
(-1150 2300);
DISPLAY 1.404255 (-1150 2300);
PAINT ORANGE (-1150 2300);
DISPLAY INVISIBLE (-1150 2300);
FORCEPROP 2 LAST BOM_COST SM_CONTROLLER
J 0
(-1150 2200);
PAINT MONO (-1150 2200);
DISPLAY INVISIBLE (-1150 2200);
FORCEPROP 2 LAST CDS_LIB mstr_discrete
J 0
(-1100 2100);
PAINT MONO (-1100 2100);
DISPLAY INVISIBLE (-1100 2100);
FORCEADD RES..1
(-1200 900);
FORCEPROP 1 LASTPIN (-1300 900) $PN 1
J 0
(-1288 912);
DISPLAY 0.617021 (-1288 912);
PAINT MONO (-1288 912);
FORCEPROP 1 LASTPIN (-1100 900) $PN 2
J 0
(-1138 912);
DISPLAY 0.617021 (-1138 912);
PAINT MONO (-1138 912);
FORCEPROP 1 LAST PACK_TYPE 0402
J 0
(-825 850);
DISPLAY 0.617021 (-825 850);
PAINT SKYBLUE (-825 850);
FORCEPROP 1 LAST PART_NUMBER G21796-066
J 0
(-1100 850);
DISPLAY 0.617021 (-1100 850);
PAINT BLUE (-1100 850);
FORCEPROP 1 LAST MATERIAL CHIP
J 0
(-1250 850);
DISPLAY 0.617021 (-1250 850);
PAINT SKYBLUE (-1250 850);
FORCEPROP 1 LAST WATTAGE 1/16W
J 2
(-1300 850);
DISPLAY 0.617021 (-1300 850);
PAINT SKYBLUE (-1300 850);
FORCEPROP 1 LAST TOLERANCE 1%
J 0
(-1550 850);
DISPLAY 0.617021 (-1550 850);
PAINT SKYBLUE (-1550 850);
FORCEPROP 1 LAST LOCATION R7M8
J 0
(-1775 850);
DISPLAY 0.617021 (-1775 850);
PAINT AQUA (-1775 850);
FORCEPROP 1 LAST VALUE 10.0
J 2
(-1575 850);
DISPLAY 0.617021 (-1575 850);
PAINT SKYBLUE (-1575 850);
FORCEPROP 2 LAST ROOM MEM
J 0
(-1250 1000);
PAINT MONO (-1250 1000);
DISPLAY INVISIBLE (-1250 1000);
FORCEPROP 1 LAST PATH I112
J 0
(-1250 1050);
DISPLAY 0.978723 (-1250 1050);
PAINT WHITE (-1250 1050);
DISPLAY INVISIBLE (-1250 1050);
FORCEPROP 2 LAST CDS_LOCATION R7M8
J 0
(-1300 950);
DISPLAY 0.617021 (-1300 950);
PAINT AQUA (-1300 950);
DISPLAY INVISIBLE (-1300 950);
FORCEPROP 2 LAST $SEC 1
J 0
(-1250 1100);
DISPLAY 0.936170 (-1250 1100);
PAINT MONO (-1250 1100);
DISPLAY INVISIBLE (-1250 1100);
FORCEPROP 2 LAST CDS_SEC 1
J 0
(-1250 1100);
DISPLAY 1.404255 (-1250 1100);
PAINT ORANGE (-1250 1100);
DISPLAY INVISIBLE (-1250 1100);
FORCEPROP 2 LAST CDS_LIB mstr_discrete
J 0
(-1200 900);
PAINT MONO (-1200 900);
DISPLAY INVISIBLE (-1200 900);
FORCEPROP 2 LAST BOM_COST SM_CONTROLLER
J 0
(-1250 1000);
PAINT MONO (-1250 1000);
DISPLAY INVISIBLE (-1250 1000);
FORCEADD PVPP_ABC..1
(1475 5100);
FORCEPROP 3 LASTPIN (1475 5050) SIG_NAME PVPP_ABC\g
J 0
(1485 5060);
DISPLAY 0.659574 (1485 5060);
PAINT MONO (1485 5060);
DISPLAY INVISIBLE (1485 5060);
FORCEPROP 2 LAST ROOM SMB
J 0
(1475 5175);
PAINT MONO (1475 5175);
DISPLAY INVISIBLE (1475 5175);
FORCEPROP 1 LAST PATH I113
J 0
(1525 5125);
DISPLAY 0.872340 (1525 5125);
PAINT AQUA (1525 5125);
DISPLAY INVISIBLE (1525 5125);
FORCEPROP 2 LAST CDS_LIB mstr_symbols
J 0
(1475 5100);
PAINT ORANGE (1475 5100);
DISPLAY INVISIBLE (1475 5100);
FORCEPROP 2 LAST BOM_COST SM_CONTROLLER
J 0
(1475 5200);
DISPLAY 1.617021 (1475 5200);
PAINT ORANGE (1475 5200);
DISPLAY INVISIBLE (1475 5200);
FORCEPROP 1 LAST VOLTAGE 2.5V
J 0
(1430 5057);
DISPLAY 0.340426 (1430 5057);
PAINT SKYBLUE (1430 5057);
DISPLAY INVISIBLE (1430 5057);
FORCEPROP 1 LAST BODY_TYPE PLUMBING
J 0
(1430 5057);
DISPLAY 0.340426 (1430 5057);
PAINT GREEN (1430 5057);
DISPLAY INVISIBLE (1430 5057);
FORCEPROP 1 LAST HDL_POWER PVPP_ABC
J 1
(1475 5150);
DISPLAY 0.872340 (1475 5150);
PAINT GREEN (1475 5150);
DISPLAY INVISIBLE (1475 5150);
FORCEADD PVPP_ABC..1
(650 4625);
FORCEPROP 3 LASTPIN (650 4575) SIG_NAME PVPP_ABC\g
J 0
(660 4585);
DISPLAY 0.659574 (660 4585);
PAINT MONO (660 4585);
DISPLAY INVISIBLE (660 4585);
FORCEPROP 2 LAST ROOM SMB
J 0
(650 4700);
PAINT MONO (650 4700);
DISPLAY INVISIBLE (650 4700);
FORCEPROP 1 LAST PATH I114
J 0
(700 4650);
DISPLAY 0.872340 (700 4650);
PAINT AQUA (700 4650);
DISPLAY INVISIBLE (700 4650);
FORCEPROP 2 LAST CDS_LIB mstr_symbols
J 0
(650 4625);
PAINT ORANGE (650 4625);
DISPLAY INVISIBLE (650 4625);
FORCEPROP 2 LAST BOM_COST SM_CONTROLLER
J 0
(650 4725);
DISPLAY 1.617021 (650 4725);
PAINT ORANGE (650 4725);
DISPLAY INVISIBLE (650 4725);
FORCEPROP 1 LAST VOLTAGE 2.5V
J 0
(605 4582);
DISPLAY 0.340426 (605 4582);
PAINT SKYBLUE (605 4582);
DISPLAY INVISIBLE (605 4582);
FORCEPROP 1 LAST BODY_TYPE PLUMBING
J 0
(605 4582);
DISPLAY 0.340426 (605 4582);
PAINT GREEN (605 4582);
DISPLAY INVISIBLE (605 4582);
FORCEPROP 1 LAST HDL_POWER PVPP_ABC
J 1
(650 4675);
DISPLAY 0.872340 (650 4675);
PAINT GREEN (650 4675);
DISPLAY INVISIBLE (650 4675);
FORCEADD RES..1
(1600 2100);
FORCEPROP 1 LASTPIN (1500 2100) $PN 1
J 0
(1512 2112);
DISPLAY 0.617021 (1512 2112);
PAINT MONO (1512 2112);
FORCEPROP 1 LASTPIN (1700 2100) $PN 2
J 0
(1662 2112);
DISPLAY 0.617021 (1662 2112);
PAINT MONO (1662 2112);
FORCEPROP 1 LAST MATERIAL CHIP
J 0
(1750 2050);
DISPLAY 0.617021 (1750 2050);
PAINT SKYBLUE (1750 2050);
FORCEPROP 1 LAST PART_NUMBER G21796-173
J 0
(1900 2050);
DISPLAY 0.617021 (1900 2050);
PAINT BLUE (1900 2050);
FORCEPROP 1 LAST PACK_TYPE 0402
J 0
(2150 2050);
DISPLAY 0.617021 (2150 2050);
PAINT SKYBLUE (2150 2050);
FORCEPROP 1 LAST LOCATION R6U14
J 0
(1150 2050);
DISPLAY 0.617021 (1150 2050);
PAINT AQUA (1150 2050);
FORCEPROP 1 LAST WATTAGE 1/16W
J 2
(1700 2050);
DISPLAY 0.617021 (1700 2050);
PAINT SKYBLUE (1700 2050);
FORCEPROP 1 LAST TOLERANCE 1%
J 0
(1450 2050);
DISPLAY 0.617021 (1450 2050);
PAINT SKYBLUE (1450 2050);
FORCEPROP 1 LAST VALUE 20.0
J 2
(1400 2050);
DISPLAY 0.617021 (1400 2050);
PAINT SKYBLUE (1400 2050);
FORCEPROP 2 LAST ROOM MEM
J 0
(1800 2200);
DISPLAY 1.404255 (1800 2200);
PAINT ORANGE (1800 2200);
DISPLAY INVISIBLE (1800 2200);
FORCEPROP 2 LAST $SEC 1
J 0
(1550 2300);
DISPLAY 0.936170 (1550 2300);
PAINT MONO (1550 2300);
DISPLAY INVISIBLE (1550 2300);
FORCEPROP 2 LAST CDS_SEC 1
J 0
(1550 2300);
DISPLAY 1.404255 (1550 2300);
PAINT ORANGE (1550 2300);
DISPLAY INVISIBLE (1550 2300);
FORCEPROP 2 LAST CDS_LIB mstr_discrete
J 0
(1600 2100);
PAINT ORANGE (1600 2100);
DISPLAY INVISIBLE (1600 2100);
FORCEPROP 1 LAST PATH I115
J 0
(1550 2250);
DISPLAY 0.978723 (1550 2250);
PAINT WHITE (1550 2250);
DISPLAY INVISIBLE (1550 2250);
FORCEPROP 2 LAST CDS_LOCATION R6U14
J 0
(1550 2175);
DISPLAY 0.617021 (1550 2175);
PAINT AQUA (1550 2175);
DISPLAY INVISIBLE (1550 2175);
FORCEADD PVPP_ABC..1
(875 4950);
FORCEPROP 3 LASTPIN (875 4900) SIG_NAME PVPP_ABC\g
J 0
(885 4910);
DISPLAY 0.659574 (885 4910);
PAINT MONO (885 4910);
DISPLAY INVISIBLE (885 4910);
FORCEPROP 2 LAST ROOM SMB
J 0
(875 5025);
PAINT MONO (875 5025);
DISPLAY INVISIBLE (875 5025);
FORCEPROP 1 LAST PATH I12
J 0
(925 4975);
DISPLAY 0.872340 (925 4975);
PAINT AQUA (925 4975);
DISPLAY INVISIBLE (925 4975);
FORCEPROP 2 LAST CDS_LIB mstr_symbols
J 0
(875 4950);
PAINT ORANGE (875 4950);
DISPLAY INVISIBLE (875 4950);
FORCEPROP 2 LAST BOM_COST SM_CONTROLLER
J 0
(875 5050);
DISPLAY 1.617021 (875 5050);
PAINT ORANGE (875 5050);
DISPLAY INVISIBLE (875 5050);
FORCEPROP 1 LAST VOLTAGE 2.5V
J 0
(830 4907);
DISPLAY 0.340426 (830 4907);
PAINT SKYBLUE (830 4907);
DISPLAY INVISIBLE (830 4907);
FORCEPROP 1 LAST BODY_TYPE PLUMBING
J 0
(830 4907);
DISPLAY 0.340426 (830 4907);
PAINT GREEN (830 4907);
DISPLAY INVISIBLE (830 4907);
FORCEPROP 1 LAST HDL_POWER PVPP_ABC
J 1
(875 5000);
DISPLAY 0.872340 (875 5000);
PAINT GREEN (875 5000);
DISPLAY INVISIBLE (875 5000);
FORCEADD RES..2
(875 4650);
FORCEPROP 1 LAST PART_NUMBER G21796-235
J 0
(915 4525);
DISPLAY 0.617021 (915 4525);
PAINT BLUE (915 4525);
FORCEPROP 1 LAST MATERIAL CHIP
J 0
(915 4575);
DISPLAY 0.617021 (915 4575);
PAINT SKYBLUE (915 4575);
FORCEPROP 1 LAST PACK_TYPE 0402
J 0
(915 4475);
DISPLAY 0.617021 (915 4475);
PAINT SKYBLUE (915 4475);
FORCEPROP 1 LAST WATTAGE 1/16W
J 0
(915 4625);
DISPLAY 0.617021 (915 4625);
PAINT SKYBLUE (915 4625);
FORCEPROP 1 LAST TOLERANCE 1.0%
J 0
(920 4675);
DISPLAY 0.617021 (920 4675);
PAINT SKYBLUE (920 4675);
FORCEPROP 1 LAST LOCATION R4T7
J 0
(920 4775);
DISPLAY 0.617021 (920 4775);
PAINT AQUA (920 4775);
FORCEPROP 1 LASTPIN (875 4750) $PN 1
J 0
(880 4712);
DISPLAY 0.617021 (880 4712);
PAINT MONO (880 4712);
FORCEPROP 1 LASTPIN (875 4550) $PN 2
J 0
(880 4560);
DISPLAY 0.617021 (880 4560);
PAINT MONO (880 4560);
FORCEPROP 1 LAST VALUE 665
J 0
(920 4725);
DISPLAY 0.617021 (920 4725);
PAINT SKYBLUE (920 4725);
FORCEPROP 2 LAST ROOM MEM
J 0
(925 4825);
PAINT MONO (925 4825);
DISPLAY INVISIBLE (925 4825);
FORCEPROP 1 LAST PATH I13
J 0
(925 4825);
DISPLAY 0.978723 (925 4825);
PAINT WHITE (925 4825);
DISPLAY INVISIBLE (925 4825);
FORCEPROP 2 LAST CDS_LOCATION R4T7
J 0
(920 4775);
DISPLAY 0.617021 (920 4775);
PAINT AQUA (920 4775);
DISPLAY INVISIBLE (920 4775);
FORCEPROP 2 LAST SEC 1
J 0
(925 4875);
DISPLAY 0.936170 (925 4875);
PAINT MONO (925 4875);
DISPLAY INVISIBLE (925 4875);
FORCEPROP 2 LAST SEC_TYPE 0402
J 0
(925 4875);
DISPLAY 1.021277 (925 4875);
PAINT ORANGE (925 4875);
DISPLAY INVISIBLE (925 4875);
FORCEPROP 2 LAST BOM_COST SM_CONTROLLER
J 0
(925 4825);
PAINT MONO (925 4825);
DISPLAY INVISIBLE (925 4825);
FORCEPROP 2 LAST CDS_LIB mstr_discrete
J 0
(875 4650);
PAINT ORANGE (875 4650);
DISPLAY INVISIBLE (875 4650);
FORCEADD PCA9617..1
(150 4300);
FORCEPROP 1 LAST MATERIAL IC
J 0
(-200 4575);
DISPLAY 0.617021 (-200 4575);
PAINT SKYBLUE (-200 4575);
FORCEPROP 2 LASTPIN (550 4350) $PN 7
J 0
(560 4360);
DISPLAY 0.617021 (560 4360);
PAINT MONO (560 4360);
FORCEPROP 2 LASTPIN (-250 4200) $PN 5
J 2
(-260 4210);
DISPLAY 0.617021 (-260 4210);
PAINT MONO (-260 4210);
FORCEPROP 2 LASTPIN (-250 4350) $PN 2
J 2
(-260 4360);
DISPLAY 0.617021 (-260 4360);
PAINT MONO (-260 4360);
FORCEPROP 2 LASTPIN (-250 4300) $PN 3
J 2
(-260 4310);
DISPLAY 0.617021 (-260 4310);
PAINT MONO (-260 4310);
FORCEPROP 2 LASTPIN (550 4300) $PN 6
J 0
(560 4310);
DISPLAY 0.617021 (560 4310);
PAINT MONO (560 4310);
FORCEPROP 2 LASTPIN (-250 4450) $PN 1
J 2
(-260 4460);
DISPLAY 0.617021 (-260 4460);
PAINT MONO (-260 4460);
FORCEPROP 2 LASTPIN (550 4450) $PN 8
J 0
(560 4460);
DISPLAY 0.617021 (560 4460);
PAINT MONO (560 4460);
FORCEPROP 1 LAST PART_NUMBER G81764-001
J 0
(-200 4100);
DISPLAY 0.617021 (-200 4100);
PAINT BLUE (-200 4100);
FORCEPROP 1 LAST LOCATION U6F1
J 0
(-200 4625);
DISPLAY 0.617021 (-200 4625);
PAINT AQUA (-200 4625);
FORCEPROP 1 LAST POWER_GROUP GND=GND
J 0
(-200 4050);
DISPLAY 0.617021 (-200 4050);
PAINT ORANGE (-200 4050);
FORCEPROP 2 LAST ROOM MEM
J 0
(-200 4675);
PAINT MONO (-200 4675);
DISPLAY INVISIBLE (-200 4675);
FORCEPROP 1 LAST PATH I15
J 0
(275 4575);
PAINT GREEN (275 4575);
DISPLAY INVISIBLE (275 4575);
FORCEPROP 2 LAST CDS_LOCATION U6F1
J 0
(-200 4625);
DISPLAY 0.617021 (-200 4625);
PAINT AQUA (-200 4625);
DISPLAY INVISIBLE (-200 4625);
FORCEPROP 2 LAST $SEC 1
J 0
(-200 4675);
DISPLAY 0.936170 (-200 4675);
PAINT MONO (-200 4675);
DISPLAY INVISIBLE (-200 4675);
FORCEPROP 2 LAST CDS_SEC 1
J 0
(-200 4675);
DISPLAY 1.404255 (-200 4675);
PAINT ORANGE (-200 4675);
DISPLAY INVISIBLE (-200 4675);
FORCEPROP 2 LAST BOM_COST SM_CONTROLLER
J 0
(-200 4675);
PAINT MONO (-200 4675);
DISPLAY INVISIBLE (-200 4675);
FORCEPROP 2 LAST CDS_LIB mstr_digital
J 0
(150 4300);
PAINT MONO (150 4300);
DISPLAY INVISIBLE (150 4300);
FORCEPROP 1 LAST PACK_TYPE SSOP
J 0
(-200 4675);
PAINT SKYBLUE (-200 4675);
DISPLAY INVISIBLE (-200 4675);
FORCEADD PVCCIO_CPU0..1
(-475 4875);
FORCEPROP 3 LASTPIN (-475 4825) SIG_NAME PVCCIO_CPU0\g
J 0
(-465 4835);
DISPLAY 0.659574 (-465 4835);
PAINT MONO (-465 4835);
DISPLAY INVISIBLE (-465 4835);
FORCEPROP 1 LAST PATH I16
J 0
(-425 4900);
DISPLAY 0.872340 (-425 4900);
PAINT AQUA (-425 4900);
DISPLAY INVISIBLE (-425 4900);
FORCEPROP 2 LAST CDS_LIB mstr_symbols
J 0
(-475 4875);
PAINT ORANGE (-475 4875);
DISPLAY INVISIBLE (-475 4875);
FORCEPROP 1 LAST VOLTAGE 1.1V
J 0
(-520 4832);
DISPLAY 0.340426 (-520 4832);
PAINT SKYBLUE (-520 4832);
DISPLAY INVISIBLE (-520 4832);
FORCEPROP 1 LAST BODY_TYPE PLUMBING
J 0
(-520 4832);
DISPLAY 0.340426 (-520 4832);
PAINT GREEN (-520 4832);
DISPLAY INVISIBLE (-520 4832);
FORCEPROP 1 LAST HDL_POWER PVCCIO_CPU0
J 1
(-475 4925);
DISPLAY 0.872340 (-475 4925);
PAINT GREEN (-475 4925);
DISPLAY INVISIBLE (-475 4925);
FORCEADD RES..2
R 2
(-650 4650);
FORCEPROP 1 LASTPIN (-650 4550) $PN 2
J 2
(-655 4560);
DISPLAY 0.617021 (-655 4560);
PAINT MONO (-655 4560);
FORCEPROP 1 LAST VALUE 240
J 2
(-695 4725);
DISPLAY 0.617021 (-695 4725);
PAINT SKYBLUE (-695 4725);
FORCEPROP 1 LAST LOCATION R4T6
J 2
(-695 4775);
DISPLAY 0.617021 (-695 4775);
PAINT AQUA (-695 4775);
FORCEPROP 1 LASTPIN (-650 4750) $PN 1
J 2
(-655 4712);
DISPLAY 0.617021 (-655 4712);
PAINT MONO (-655 4712);
FORCEPROP 1 LAST TOLERANCE 1.0%
J 2
(-695 4675);
DISPLAY 0.617021 (-695 4675);
PAINT SKYBLUE (-695 4675);
FORCEPROP 1 LAST WATTAGE 1/16W
J 2
(-690 4625);
DISPLAY 0.617021 (-690 4625);
PAINT SKYBLUE (-690 4625);
FORCEPROP 1 LAST MATERIAL CHIP
J 2
(-690 4575);
DISPLAY 0.617021 (-690 4575);
PAINT SKYBLUE (-690 4575);
FORCEPROP 1 LAST PART_NUMBER G21796-294
J 2
(-690 4525);
DISPLAY 0.617021 (-690 4525);
PAINT BLUE (-690 4525);
FORCEPROP 1 LAST PACK_TYPE 0402
J 2
(-690 4475);
DISPLAY 0.617021 (-690 4475);
PAINT SKYBLUE (-690 4475);
FORCEPROP 2 LAST ROOM MEM
J 0
(-675 4800);
PAINT MONO (-675 4800);
DISPLAY INVISIBLE (-675 4800);
FORCEPROP 1 LAST PATH I17
J 2
(-700 4825);
DISPLAY 0.978723 (-700 4825);
PAINT WHITE (-700 4825);
DISPLAY INVISIBLE (-700 4825);
FORCEPROP 2 LAST CDS_LOCATION R4T6
J 2
(-695 4775);
DISPLAY 0.617021 (-695 4775);
PAINT AQUA (-695 4775);
DISPLAY INVISIBLE (-695 4775);
FORCEPROP 2 LAST $SEC 1
J 0
(-700 4875);
DISPLAY 0.936170 (-700 4875);
PAINT MONO (-700 4875);
DISPLAY INVISIBLE (-700 4875);
FORCEPROP 2 LAST CDS_SEC 1
J 0
(-700 4875);
DISPLAY 1.404255 (-700 4875);
PAINT ORANGE (-700 4875);
DISPLAY INVISIBLE (-700 4875);
FORCEPROP 2 LAST BOM_COST SM_CONTROLLER
J 2
(-1225 4750);
DISPLAY 1.617021 (-1225 4750);
PAINT PEACH (-1225 4750);
DISPLAY INVISIBLE (-1225 4750);
FORCEPROP 2 LAST CD_SEC 1
J 0
(-700 4900);
DISPLAY 1.617021 (-700 4900);
PAINT MONO (-700 4900);
DISPLAY INVISIBLE (-700 4900);
FORCEPROP 2 LAST SIGNAL_MODEL DEFAULT_RESISTOR_750OHM_2_1
J 0
(-700 4900);
DISPLAY 1.617021 (-700 4900);
PAINT MONO (-700 4900);
DISPLAY INVISIBLE (-700 4900);
FORCEPROP 2 LAST CDS_LIB mstr_discrete
J 0
(-650 4650);
PAINT MONO (-650 4650);
DISPLAY INVISIBLE (-650 4650);
FORCEADD PVCCIO_CPU0..1
(-900 4975);
FORCEPROP 3 LASTPIN (-900 4925) SIG_NAME PVCCIO_CPU0\g
J 0
(-890 4935);
DISPLAY 0.659574 (-890 4935);
PAINT MONO (-890 4935);
DISPLAY INVISIBLE (-890 4935);
FORCEPROP 1 LAST PATH I18
J 0
(-850 5000);
DISPLAY 0.872340 (-850 5000);
PAINT AQUA (-850 5000);
DISPLAY INVISIBLE (-850 5000);
FORCEPROP 2 LAST CDS_LIB mstr_symbols
J 0
(-900 4975);
PAINT ORANGE (-900 4975);
DISPLAY INVISIBLE (-900 4975);
FORCEPROP 1 LAST VOLTAGE 1.1V
J 0
(-945 4932);
DISPLAY 0.340426 (-945 4932);
PAINT SKYBLUE (-945 4932);
DISPLAY INVISIBLE (-945 4932);
FORCEPROP 1 LAST BODY_TYPE PLUMBING
J 0
(-945 4932);
DISPLAY 0.340426 (-945 4932);
PAINT GREEN (-945 4932);
DISPLAY INVISIBLE (-945 4932);
FORCEPROP 1 LAST HDL_POWER PVCCIO_CPU0
J 1
(-900 5025);
DISPLAY 0.872340 (-900 5025);
PAINT GREEN (-900 5025);
DISPLAY INVISIBLE (-900 5025);
FORCEADD RES..2
R 2
(-1025 4650);
FORCEPROP 1 LAST PART_NUMBER G21796-294
J 2
(-1065 4525);
DISPLAY 0.617021 (-1065 4525);
PAINT BLUE (-1065 4525);
FORCEPROP 1 LASTPIN (-1025 4550) $PN 2
J 2
(-1030 4560);
DISPLAY 0.617021 (-1030 4560);
PAINT MONO (-1030 4560);
FORCEPROP 1 LAST LOCATION R4T5
J 2
(-1070 4775);
DISPLAY 0.617021 (-1070 4775);
PAINT AQUA (-1070 4775);
FORCEPROP 1 LAST VALUE 240
J 2
(-1070 4725);
DISPLAY 0.617021 (-1070 4725);
PAINT SKYBLUE (-1070 4725);
FORCEPROP 1 LAST WATTAGE 1/16W
J 2
(-1065 4625);
DISPLAY 0.617021 (-1065 4625);
PAINT SKYBLUE (-1065 4625);
FORCEPROP 1 LAST MATERIAL CHIP
J 2
(-1065 4575);
DISPLAY 0.617021 (-1065 4575);
PAINT SKYBLUE (-1065 4575);
FORCEPROP 1 LASTPIN (-1025 4750) $PN 1
J 2
(-1030 4712);
DISPLAY 0.617021 (-1030 4712);
PAINT MONO (-1030 4712);
FORCEPROP 1 LAST TOLERANCE 1.0%
J 2
(-1070 4675);
DISPLAY 0.617021 (-1070 4675);
PAINT SKYBLUE (-1070 4675);
FORCEPROP 1 LAST PACK_TYPE 0402
J 2
(-1065 4475);
DISPLAY 0.617021 (-1065 4475);
PAINT SKYBLUE (-1065 4475);
FORCEPROP 2 LAST ROOM MEM
J 0
(-1050 4800);
PAINT MONO (-1050 4800);
DISPLAY INVISIBLE (-1050 4800);
FORCEPROP 1 LAST PATH I19
J 2
(-1075 4825);
DISPLAY 0.978723 (-1075 4825);
PAINT WHITE (-1075 4825);
DISPLAY INVISIBLE (-1075 4825);
FORCEPROP 2 LAST CDS_LOCATION R4T5
J 2
(-1070 4775);
DISPLAY 0.617021 (-1070 4775);
PAINT AQUA (-1070 4775);
DISPLAY INVISIBLE (-1070 4775);
FORCEPROP 2 LAST $SEC 1
J 0
(-1075 4875);
DISPLAY 0.936170 (-1075 4875);
PAINT MONO (-1075 4875);
DISPLAY INVISIBLE (-1075 4875);
FORCEPROP 2 LAST CDS_SEC 1
J 0
(-1075 4875);
DISPLAY 1.404255 (-1075 4875);
PAINT ORANGE (-1075 4875);
DISPLAY INVISIBLE (-1075 4875);
FORCEPROP 2 LAST BOM_COST SM_CONTROLLER
J 2
(-1600 4750);
DISPLAY 1.617021 (-1600 4750);
PAINT PEACH (-1600 4750);
DISPLAY INVISIBLE (-1600 4750);
FORCEPROP 2 LAST CDS_LIB mstr_discrete
J 0
(-1025 4650);
PAINT MONO (-1025 4650);
DISPLAY INVISIBLE (-1025 4650);
FORCEPROP 2 LAST SIGNAL_MODEL DEFAULT_RESISTOR_750OHM_2_1
J 0
(-1075 4900);
DISPLAY 1.617021 (-1075 4900);
PAINT MONO (-1075 4900);
DISPLAY INVISIBLE (-1075 4900);
FORCEPROP 2 LAST CD_SEC 1
J 0
(-1075 4900);
DISPLAY 1.617021 (-1075 4900);
PAINT MONO (-1075 4900);
DISPLAY INVISIBLE (-1075 4900);
FORCEADD CAP_A..1
(1900 4925);
FORCEPROP 1 LAST PACK_TYPE 0402V
J 0
(1950 4725);
DISPLAY 0.617021 (1950 4725);
PAINT SKYBLUE (1950 4725);
FORCEPROP 1 LAST PART_NUMBER A36096-030
J 0
(1950 4775);
DISPLAY 0.617021 (1950 4775);
PAINT BLUE (1950 4775);
FORCEPROP 1 LAST TOLERANCE 10%
J 0
(1950 4875);
DISPLAY 0.617021 (1950 4875);
PAINT SKYBLUE (1950 4875);
FORCEPROP 1 LAST VOLTAGE 16V
J 0
(1950 4925);
DISPLAY 0.617021 (1950 4925);
PAINT SKYBLUE (1950 4925);
FORCEPROP 1 LAST VALUE 0.1UF
J 0
(1950 4975);
DISPLAY 0.617021 (1950 4975);
PAINT SKYBLUE (1950 4975);
FORCEPROP 1 LAST LOCATION C6F2
J 0
(1950 5025);
DISPLAY 0.617021 (1950 5025);
PAINT AQUA (1950 5025);
FORCEPROP 1 LASTPIN (1900 4825) $PN 2
J 0
(1910 4805);
DISPLAY 0.617021 (1910 4805);
PAINT MONO (1910 4805);
FORCEPROP 1 LASTPIN (1900 5025) $PN 1
J 0
(1910 5005);
DISPLAY 0.617021 (1910 5005);
PAINT MONO (1910 5005);
FORCEPROP 1 LAST MATERIAL X7R
J 0
(1950 4825);
DISPLAY 0.617021 (1950 4825);
PAINT SKYBLUE (1950 4825);
FORCEPROP 2 LAST $SEC 1
J 0
(1950 5125);
DISPLAY 0.936170 (1950 5125);
PAINT MONO (1950 5125);
DISPLAY INVISIBLE (1950 5125);
FORCEPROP 2 LAST CDS_SEC 1
J 0
(1950 5125);
DISPLAY 1.404255 (1950 5125);
PAINT ORANGE (1950 5125);
DISPLAY INVISIBLE (1950 5125);
FORCEPROP 2 LAST CDS_LIB dev_discrete
J 0
(1900 4925);
PAINT ORANGE (1900 4925);
DISPLAY INVISIBLE (1900 4925);
FORCEPROP 2 LAST SIGNAL_MODEL DEFAULT_CAPACITOR_100000pF_2_1
J 0
(1950 5150);
DISPLAY 1.617021 (1950 5150);
PAINT MONO (1950 5150);
DISPLAY INVISIBLE (1950 5150);
FORCEPROP 2 LAST CD_SEC 1
J 0
(1950 5150);
DISPLAY 1.617021 (1950 5150);
PAINT MONO (1950 5150);
DISPLAY INVISIBLE (1950 5150);
FORCEPROP 2 LAST BOM_COST SM_CONTROLLER
J 0
(1950 5075);
DISPLAY 2.170213 (1950 5075);
PAINT ORANGE (1950 5075);
DISPLAY INVISIBLE (1950 5075);
FORCEPROP 2 LAST CDS_LOCATION C6F2
J 0
(1950 5025);
DISPLAY 0.617021 (1950 5025);
PAINT AQUA (1950 5025);
DISPLAY INVISIBLE (1950 5025);
FORCEPROP 2 LAST ROOM MEM
J 0
(1950 5050);
PAINT MONO (1950 5050);
DISPLAY INVISIBLE (1950 5050);
FORCEPROP 1 LAST PATH I2
J 0
(1950 5075);
DISPLAY 0.978723 (1950 5075);
PAINT WHITE (1950 5075);
DISPLAY INVISIBLE (1950 5075);
FORCEADD RES..1
(-1075 4300);
FORCEPROP 1 LAST LOCATION R4T4
J 0
(-1575 4250);
DISPLAY 0.617021 (-1575 4250);
PAINT AQUA (-1575 4250);
FORCEPROP 1 LAST MATERIAL CHIP
J 0
(-700 4250);
DISPLAY 0.617021 (-700 4250);
PAINT SKYBLUE (-700 4250);
FORCEPROP 1 LAST PACK_TYPE 0402
J 0
(-550 4250);
DISPLAY 0.617021 (-550 4250);
PAINT SKYBLUE (-550 4250);
FORCEPROP 1 LASTPIN (-975 4300) $PN 2
J 0
(-1013 4312);
DISPLAY 0.617021 (-1013 4312);
PAINT MONO (-1013 4312);
FORCEPROP 1 LAST TOLERANCE 1%
J 0
(-1275 4250);
DISPLAY 0.617021 (-1275 4250);
PAINT SKYBLUE (-1275 4250);
FORCEPROP 1 LAST VALUE 10.0
J 2
(-1325 4250);
DISPLAY 0.617021 (-1325 4250);
PAINT SKYBLUE (-1325 4250);
FORCEPROP 1 LASTPIN (-1175 4300) $PN 1
J 0
(-1163 4312);
DISPLAY 0.617021 (-1163 4312);
PAINT MONO (-1163 4312);
FORCEPROP 1 LAST PART_NUMBER G21796-066
J 0
(-1000 4250);
DISPLAY 0.617021 (-1000 4250);
PAINT BLUE (-1000 4250);
FORCEPROP 1 LAST WATTAGE 1/16W
J 2
(-1050 4250);
DISPLAY 0.617021 (-1050 4250);
PAINT SKYBLUE (-1050 4250);
FORCEPROP 2 LAST ROOM MEM
J 0
(-1125 4400);
PAINT MONO (-1125 4400);
DISPLAY INVISIBLE (-1125 4400);
FORCEPROP 1 LAST PATH I20
J 0
(-1125 4450);
DISPLAY 0.978723 (-1125 4450);
PAINT WHITE (-1125 4450);
DISPLAY INVISIBLE (-1125 4450);
FORCEPROP 2 LAST CDS_LOCATION R4T4
J 0
(-1175 4350);
DISPLAY 0.617021 (-1175 4350);
PAINT AQUA (-1175 4350);
DISPLAY INVISIBLE (-1175 4350);
FORCEPROP 2 LAST $SEC 1
J 0
(-1125 4500);
DISPLAY 0.936170 (-1125 4500);
PAINT MONO (-1125 4500);
DISPLAY INVISIBLE (-1125 4500);
FORCEPROP 2 LAST CDS_SEC 1
J 0
(-1125 4500);
DISPLAY 1.404255 (-1125 4500);
PAINT ORANGE (-1125 4500);
DISPLAY INVISIBLE (-1125 4500);
FORCEPROP 2 LAST BOM_COST SM_CONTROLLER
J 0
(-1125 4400);
PAINT MONO (-1125 4400);
DISPLAY INVISIBLE (-1125 4400);
FORCEPROP 2 LAST CDS_LIB mstr_discrete
J 0
(-1075 4300);
PAINT MONO (-1075 4300);
DISPLAY INVISIBLE (-1075 4300);
FORCEADD PVCCIO_CPU0..1
(2125 3950);
FORCEPROP 3 LASTPIN (2125 3900) SIG_NAME PVCCIO_CPU0\g
J 0
(2135 3910);
DISPLAY 0.659574 (2135 3910);
PAINT MONO (2135 3910);
DISPLAY INVISIBLE (2135 3910);
FORCEPROP 1 LAST PATH I21
J 0
(2175 3975);
DISPLAY 0.872340 (2175 3975);
PAINT AQUA (2175 3975);
DISPLAY INVISIBLE (2175 3975);
FORCEPROP 2 LAST CDS_LIB mstr_symbols
J 0
(2125 3950);
PAINT ORANGE (2125 3950);
DISPLAY INVISIBLE (2125 3950);
FORCEPROP 1 LAST VOLTAGE 1.1V
J 0
(2080 3907);
DISPLAY 0.340426 (2080 3907);
PAINT SKYBLUE (2080 3907);
DISPLAY INVISIBLE (2080 3907);
FORCEPROP 1 LAST BODY_TYPE PLUMBING
J 0
(2080 3907);
DISPLAY 0.340426 (2080 3907);
PAINT GREEN (2080 3907);
DISPLAY INVISIBLE (2080 3907);
FORCEPROP 1 LAST HDL_POWER PVCCIO_CPU0
J 1
(2125 4000);
DISPLAY 0.872340 (2125 4000);
PAINT GREEN (2125 4000);
DISPLAY INVISIBLE (2125 4000);
FORCEADD GND..1
(2125 3525);
FORCEPROP 3 LASTPIN (2125 3575) SIG_NAME GND\g
J 0
(2135 3585);
DISPLAY 0.659574 (2135 3585);
PAINT MONO (2135 3585);
DISPLAY INVISIBLE (2135 3585);
FORCEPROP 2 LAST ROOM SMB
J 0
(2025 3600);
PAINT MONO (2025 3600);
DISPLAY INVISIBLE (2025 3600);
FORCEPROP 1 LAST PATH I22
J 0
(2200 3525);
DISPLAY 0.872340 (2200 3525);
PAINT AQUA (2200 3525);
DISPLAY INVISIBLE (2200 3525);
FORCEPROP 1 LAST SIZE 1B
J 0
(2200 3475);
DISPLAY 2.361702 (2200 3475);
PAINT GREEN (2200 3475);
DISPLAY INVISIBLE (2200 3475);
FORCEPROP 2 LAST CDS_LIB mstr_symbols
J 0
(2125 3525);
PAINT MONO (2125 3525);
DISPLAY INVISIBLE (2125 3525);
FORCEPROP 2 LAST BOM_COST SM_CONTROLLER
J 0
(1725 3600);
DISPLAY 1.617021 (1725 3600);
PAINT ORANGE (1725 3600);
DISPLAY INVISIBLE (1725 3600);
FORCEPROP 1 LAST VOLTAGE 0
J 0
(2125 3525);
PAINT SKYBLUE (2125 3525);
DISPLAY INVISIBLE (2125 3525);
FORCEPROP 1 LAST BODY_TYPE PLUMBING
J 0
(2080 3482);
DISPLAY 0.340426 (2080 3482);
PAINT GREEN (2080 3482);
DISPLAY INVISIBLE (2080 3482);
FORCEPROP 1 LAST HDL_POWER GND
J 0
(2125 3675);
DISPLAY 2.361702 (2125 3675);
PAINT GREEN (2125 3675);
DISPLAY INVISIBLE (2125 3675);
FORCEADD CAP_A..1
(2125 3775);
FORCEPROP 1 LASTPIN (2125 3675) $PN 2
J 0
(2135 3655);
DISPLAY 0.617021 (2135 3655);
PAINT MONO (2135 3655);
FORCEPROP 1 LASTPIN (2125 3875) $PN 1
J 0
(2135 3855);
DISPLAY 0.617021 (2135 3855);
PAINT MONO (2135 3855);
FORCEPROP 1 LAST MATERIAL X7R
J 0
(2175 3675);
DISPLAY 0.617021 (2175 3675);
PAINT SKYBLUE (2175 3675);
FORCEPROP 1 LAST VOLTAGE 16V
J 0
(2175 3775);
DISPLAY 0.617021 (2175 3775);
PAINT SKYBLUE (2175 3775);
FORCEPROP 1 LAST PACK_TYPE 0402V
J 0
(2175 3575);
DISPLAY 0.617021 (2175 3575);
PAINT SKYBLUE (2175 3575);
FORCEPROP 1 LAST TOLERANCE 10%
J 0
(2175 3725);
DISPLAY 0.617021 (2175 3725);
PAINT SKYBLUE (2175 3725);
FORCEPROP 1 LAST VALUE 0.1UF
J 0
(2175 3825);
DISPLAY 0.617021 (2175 3825);
PAINT SKYBLUE (2175 3825);
FORCEPROP 1 LAST LOCATION C7E1
J 0
(2175 3875);
DISPLAY 0.617021 (2175 3875);
PAINT AQUA (2175 3875);
FORCEPROP 1 LAST PART_NUMBER A36096-030
J 0
(2175 3625);
DISPLAY 0.617021 (2175 3625);
PAINT BLUE (2175 3625);
FORCEPROP 2 LAST $SEC 1
J 0
(2175 3975);
DISPLAY 0.936170 (2175 3975);
PAINT MONO (2175 3975);
DISPLAY INVISIBLE (2175 3975);
FORCEPROP 2 LAST CDS_SEC 1
J 0
(2175 3975);
DISPLAY 1.404255 (2175 3975);
PAINT ORANGE (2175 3975);
DISPLAY INVISIBLE (2175 3975);
FORCEPROP 2 LAST CDS_LIB dev_discrete
J 0
(2125 3775);
PAINT ORANGE (2125 3775);
DISPLAY INVISIBLE (2125 3775);
FORCEPROP 2 LAST BOM_COST SM_CONTROLLER
J 0
(2175 3925);
DISPLAY 2.170213 (2175 3925);
PAINT ORANGE (2175 3925);
DISPLAY INVISIBLE (2175 3925);
FORCEPROP 2 LAST CD_SEC 1
J 0
(2175 4000);
DISPLAY 1.617021 (2175 4000);
PAINT MONO (2175 4000);
DISPLAY INVISIBLE (2175 4000);
FORCEPROP 2 LAST SIGNAL_MODEL DEFAULT_CAPACITOR_100000pF_2_1
J 0
(2175 4000);
DISPLAY 1.617021 (2175 4000);
PAINT MONO (2175 4000);
DISPLAY INVISIBLE (2175 4000);
FORCEPROP 2 LAST CDS_LOCATION C7E1
J 0
(2175 3875);
DISPLAY 0.617021 (2175 3875);
PAINT AQUA (2175 3875);
DISPLAY INVISIBLE (2175 3875);
FORCEPROP 2 LAST ROOM MEM
J 0
(2175 3900);
PAINT MONO (2175 3900);
DISPLAY INVISIBLE (2175 3900);
FORCEPROP 1 LAST PATH I23
J 0
(2175 3925);
DISPLAY 0.978723 (2175 3925);
PAINT WHITE (2175 3925);
DISPLAY INVISIBLE (2175 3925);
FORCEADD OFFPAGE..2
(2600 3300);
FORCEPROP 2 LAST $XR5 54 
J 0
(3239 3300);
DISPLAY 0.638298 (3239 3300);
PAINT MONO (3239 3300);
FORCEPROP 2 LAST $XR4 53 
J 0
(3149 3300);
DISPLAY 0.638298 (3149 3300);
PAINT MONO (3149 3300);
FORCEPROP 2 LAST $XR3 52 
J 0
(3059 3300);
DISPLAY 0.638298 (3059 3300);
PAINT MONO (3059 3300);
FORCEPROP 2 LAST $XR2 51 
J 0
(2969 3300);
DISPLAY 0.638298 (2969 3300);
PAINT MONO (2969 3300);
FORCEPROP 2 LAST $XR1 50 
J 0
(2879 3300);
DISPLAY 0.638298 (2879 3300);
PAINT MONO (2879 3300);
FORCEPROP 2 LAST $XR0 49 
J 0
(2789 3300);
DISPLAY 0.638298 (2789 3300);
PAINT MONO (2789 3300);
FORCEPROP 2 LAST PATH I24
J 0
(2900 3350);
DISPLAY 1.021277 (2900 3350);
PAINT ORANGE (2900 3350);
DISPLAY INVISIBLE (2900 3350);
FORCEPROP 2 LAST BOM_COST SM_CONTROLLER
J 0
(2925 3350);
PAINT MONO (2925 3350);
DISPLAY INVISIBLE (2925 3350);
FORCEPROP 2 LAST CDS_LIB mstr_standard
J 0
(2600 3300);
PAINT ORANGE (2600 3300);
DISPLAY INVISIBLE (2600 3300);
FORCEPROP 1 LAST OFFPAGE TRUE
J 0
(2925 3175);
PAINT GREEN (2925 3175);
DISPLAY INVISIBLE (2925 3175);
FORCEPROP 1 LAST COMMENT_BODY TRUE
J 0
(2555 3205);
DISPLAY 0.872340 (2555 3205);
PAINT GREEN (2555 3205);
DISPLAY INVISIBLE (2555 3205);
FORCEADD OFFPAGE..3
(2600 3250);
FORCEPROP 2 LAST $XR5 54 
J 0
(3264 3250);
DISPLAY 0.638298 (3264 3250);
PAINT MONO (3264 3250);
FORCEPROP 2 LAST $XR4 53 
J 0
(3174 3250);
DISPLAY 0.638298 (3174 3250);
PAINT MONO (3174 3250);
FORCEPROP 2 LAST $XR3 52 
J 0
(3084 3250);
DISPLAY 0.638298 (3084 3250);
PAINT MONO (3084 3250);
FORCEPROP 2 LAST $XR2 51 
J 0
(2994 3250);
DISPLAY 0.638298 (2994 3250);
PAINT MONO (2994 3250);
FORCEPROP 2 LAST $XR1 50 
J 0
(2904 3250);
DISPLAY 0.638298 (2904 3250);
PAINT MONO (2904 3250);
FORCEPROP 2 LAST $XR0 49 
J 0
(2814 3250);
DISPLAY 0.638298 (2814 3250);
PAINT MONO (2814 3250);
FORCEPROP 2 LAST PATH I25
J 0
(2925 3300);
DISPLAY 1.021277 (2925 3300);
PAINT ORANGE (2925 3300);
DISPLAY INVISIBLE (2925 3300);
FORCEPROP 2 LAST BOM_COST SM_CONTROLLER
J 0
(3375 3300);
PAINT MONO (3375 3300);
DISPLAY INVISIBLE (3375 3300);
FORCEPROP 2 LAST CDS_LIB mstr_standard
J 0
(2600 3250);
PAINT MONO (2600 3250);
DISPLAY INVISIBLE (2600 3250);
FORCEPROP 2 LAST ROOM SMB
J 0
(3375 3300);
PAINT MONO (3375 3300);
DISPLAY INVISIBLE (3375 3300);
FORCEPROP 1 LAST OFFPAGE TRUE
J 0
(2925 3125);
PAINT GREEN (2925 3125);
DISPLAY INVISIBLE (2925 3125);
FORCEPROP 1 LAST COMMENT_BODY TRUE
J 0
(2550 3150);
DISPLAY 1.872340 (2550 3150);
PAINT GREEN (2550 3150);
DISPLAY INVISIBLE (2550 3150);
FORCEADD PVCCIO_CPU1..1
(2225 2875);
FORCEPROP 3 LASTPIN (2225 2825) SIG_NAME PVCCIO_CPU1\g
J 0
(2235 2835);
DISPLAY 0.659574 (2235 2835);
PAINT MONO (2235 2835);
DISPLAY INVISIBLE (2235 2835);
FORCEPROP 1 LAST PATH I26
J 0
(2275 2900);
DISPLAY 0.872340 (2275 2900);
PAINT AQUA (2275 2900);
DISPLAY INVISIBLE (2275 2900);
FORCEPROP 2 LAST CDS_LIB mstr_symbols
J 0
(2225 2875);
PAINT ORANGE (2225 2875);
DISPLAY INVISIBLE (2225 2875);
FORCEPROP 1 LAST VOLTAGE 1.1V
J 0
(2180 2832);
DISPLAY 0.340426 (2180 2832);
PAINT SKYBLUE (2180 2832);
DISPLAY INVISIBLE (2180 2832);
FORCEPROP 1 LAST BODY_TYPE PLUMBING
J 0
(2180 2832);
DISPLAY 0.340426 (2180 2832);
PAINT GREEN (2180 2832);
DISPLAY INVISIBLE (2180 2832);
FORCEPROP 1 LAST HDL_POWER PVCCIO_CPU1
J 1
(2225 2925);
DISPLAY 0.872340 (2225 2925);
PAINT GREEN (2225 2925);
DISPLAY INVISIBLE (2225 2925);
FORCEADD CAP_A..1
(2225 2700);
FORCEPROP 1 LASTPIN (2225 2600) $PN 2
J 0
(2235 2580);
DISPLAY 0.617021 (2235 2580);
PAINT MONO (2235 2580);
FORCEPROP 1 LASTPIN (2225 2800) $PN 1
J 0
(2235 2780);
DISPLAY 0.617021 (2235 2780);
PAINT MONO (2235 2780);
FORCEPROP 1 LAST PACK_TYPE 0402V
J 0
(2275 2500);
DISPLAY 0.617021 (2275 2500);
PAINT SKYBLUE (2275 2500);
FORCEPROP 1 LAST PART_NUMBER A36096-030
J 0
(2275 2550);
DISPLAY 0.617021 (2275 2550);
PAINT BLUE (2275 2550);
FORCEPROP 1 LAST MATERIAL X7R
J 0
(2275 2600);
DISPLAY 0.617021 (2275 2600);
PAINT SKYBLUE (2275 2600);
FORCEPROP 1 LAST TOLERANCE 10%
J 0
(2275 2650);
DISPLAY 0.617021 (2275 2650);
PAINT SKYBLUE (2275 2650);
FORCEPROP 1 LAST VOLTAGE 16V
J 0
(2275 2700);
DISPLAY 0.617021 (2275 2700);
PAINT SKYBLUE (2275 2700);
FORCEPROP 1 LAST VALUE 0.1UF
J 0
(2275 2750);
DISPLAY 0.617021 (2275 2750);
PAINT SKYBLUE (2275 2750);
FORCEPROP 1 LAST LOCATION C4G22
J 0
(2275 2800);
DISPLAY 0.617021 (2275 2800);
PAINT AQUA (2275 2800);
FORCEPROP 2 LAST $SEC 1
J 0
(2275 2900);
DISPLAY 0.936170 (2275 2900);
PAINT MONO (2275 2900);
DISPLAY INVISIBLE (2275 2900);
FORCEPROP 2 LAST CDS_SEC 1
J 0
(2275 2900);
DISPLAY 1.404255 (2275 2900);
PAINT ORANGE (2275 2900);
DISPLAY INVISIBLE (2275 2900);
FORCEPROP 2 LAST CDS_LIB dev_discrete
J 0
(2225 2700);
PAINT ORANGE (2225 2700);
DISPLAY INVISIBLE (2225 2700);
FORCEPROP 2 LAST BOM_COST SM_CONTROLLER
J 0
(2275 2850);
DISPLAY 2.170213 (2275 2850);
PAINT ORANGE (2275 2850);
DISPLAY INVISIBLE (2275 2850);
FORCEPROP 2 LAST CD_SEC 1
J 0
(2275 2925);
DISPLAY 1.617021 (2275 2925);
PAINT MONO (2275 2925);
DISPLAY INVISIBLE (2275 2925);
FORCEPROP 2 LAST SIGNAL_MODEL DEFAULT_CAPACITOR_100000pF_2_1
J 0
(2275 2925);
DISPLAY 1.617021 (2275 2925);
PAINT MONO (2275 2925);
DISPLAY INVISIBLE (2275 2925);
FORCEPROP 2 LAST CDS_LOCATION C4G22
J 0
(2275 2800);
DISPLAY 0.617021 (2275 2800);
PAINT AQUA (2275 2800);
DISPLAY INVISIBLE (2275 2800);
FORCEPROP 2 LAST ROOM MEM
J 0
(2275 2825);
PAINT MONO (2275 2825);
DISPLAY INVISIBLE (2275 2825);
FORCEPROP 1 LAST PATH I27
J 0
(2275 2850);
DISPLAY 0.978723 (2275 2850);
PAINT WHITE (2275 2850);
DISPLAY INVISIBLE (2275 2850);
FORCEADD GND..1
(2225 2450);
FORCEPROP 3 LASTPIN (2225 2500) SIG_NAME GND\g
J 0
(2235 2510);
DISPLAY 0.659574 (2235 2510);
PAINT MONO (2235 2510);
DISPLAY INVISIBLE (2235 2510);
FORCEPROP 2 LAST ROOM SMB
J 0
(2125 2525);
PAINT MONO (2125 2525);
DISPLAY INVISIBLE (2125 2525);
FORCEPROP 1 LAST PATH I28
J 0
(2300 2450);
DISPLAY 0.872340 (2300 2450);
PAINT AQUA (2300 2450);
DISPLAY INVISIBLE (2300 2450);
FORCEPROP 1 LAST SIZE 1B
J 0
(2300 2400);
DISPLAY 2.361702 (2300 2400);
PAINT GREEN (2300 2400);
DISPLAY INVISIBLE (2300 2400);
FORCEPROP 2 LAST CDS_LIB mstr_symbols
J 0
(2225 2450);
PAINT MONO (2225 2450);
DISPLAY INVISIBLE (2225 2450);
FORCEPROP 2 LAST BOM_COST SM_CONTROLLER
J 0
(1825 2525);
DISPLAY 1.617021 (1825 2525);
PAINT ORANGE (1825 2525);
DISPLAY INVISIBLE (1825 2525);
FORCEPROP 1 LAST VOLTAGE 0
J 0
(2225 2450);
PAINT SKYBLUE (2225 2450);
DISPLAY INVISIBLE (2225 2450);
FORCEPROP 1 LAST BODY_TYPE PLUMBING
J 0
(2180 2407);
DISPLAY 0.340426 (2180 2407);
PAINT GREEN (2180 2407);
DISPLAY INVISIBLE (2180 2407);
FORCEPROP 1 LAST HDL_POWER GND
J 0
(2225 2600);
DISPLAY 2.361702 (2225 2600);
PAINT GREEN (2225 2600);
DISPLAY INVISIBLE (2225 2600);
FORCEADD OFFPAGE..3
(2625 2100);
FORCEPROP 2 LAST $XR5 82 
J 0
(3289 2100);
DISPLAY 0.638298 (3289 2100);
PAINT MONO (3289 2100);
FORCEPROP 2 LAST $XR4 81 
J 0
(3199 2100);
DISPLAY 0.638298 (3199 2100);
PAINT MONO (3199 2100);
FORCEPROP 2 LAST $XR3 80 
J 0
(3109 2100);
DISPLAY 0.638298 (3109 2100);
PAINT MONO (3109 2100);
FORCEPROP 2 LAST $XR2 79 
J 0
(3019 2100);
DISPLAY 0.638298 (3019 2100);
PAINT MONO (3019 2100);
FORCEPROP 2 LAST $XR1 78 
J 0
(2929 2100);
DISPLAY 0.638298 (2929 2100);
PAINT MONO (2929 2100);
FORCEPROP 2 LAST $XR0 77 
J 0
(2839 2100);
DISPLAY 0.638298 (2839 2100);
PAINT MONO (2839 2100);
FORCEPROP 2 LAST PATH I29
J 0
(2950 2150);
DISPLAY 1.021277 (2950 2150);
PAINT ORANGE (2950 2150);
DISPLAY INVISIBLE (2950 2150);
FORCEPROP 2 LAST ROOM SMB
J 0
(3300 2150);
PAINT MONO (3300 2150);
DISPLAY INVISIBLE (3300 2150);
FORCEPROP 2 LAST BOM_COST SM_CONTROLLER
J 0
(3300 2150);
PAINT MONO (3300 2150);
DISPLAY INVISIBLE (3300 2150);
FORCEPROP 2 LAST CDS_LIB mstr_standard
J 0
(2625 2100);
PAINT MONO (2625 2100);
DISPLAY INVISIBLE (2625 2100);
FORCEPROP 1 LAST OFFPAGE TRUE
J 0
(2950 1975);
PAINT GREEN (2950 1975);
DISPLAY INVISIBLE (2950 1975);
FORCEPROP 1 LAST COMMENT_BODY TRUE
J 0
(2575 2000);
DISPLAY 1.872340 (2575 2000);
PAINT GREEN (2575 2000);
DISPLAY INVISIBLE (2575 2000);
FORCEADD GND..1
(1900 4675);
FORCEPROP 3 LASTPIN (1900 4725) SIG_NAME GND\g
J 0
(1910 4735);
DISPLAY 0.659574 (1910 4735);
PAINT MONO (1910 4735);
DISPLAY INVISIBLE (1910 4735);
FORCEPROP 2 LAST ROOM SMB
J 0
(1800 4750);
PAINT MONO (1800 4750);
DISPLAY INVISIBLE (1800 4750);
FORCEPROP 1 LAST PATH I3
J 0
(1975 4675);
DISPLAY 0.872340 (1975 4675);
PAINT AQUA (1975 4675);
DISPLAY INVISIBLE (1975 4675);
FORCEPROP 2 LAST BOM_COST SM_CONTROLLER
J 0
(1500 4750);
DISPLAY 1.617021 (1500 4750);
PAINT ORANGE (1500 4750);
DISPLAY INVISIBLE (1500 4750);
FORCEPROP 2 LAST CDS_LIB mstr_symbols
J 0
(1900 4675);
PAINT MONO (1900 4675);
DISPLAY INVISIBLE (1900 4675);
FORCEPROP 1 LAST SIZE 1B
J 0
(1975 4625);
DISPLAY 2.361702 (1975 4625);
PAINT GREEN (1975 4625);
DISPLAY INVISIBLE (1975 4625);
FORCEPROP 1 LAST VOLTAGE 0
J 0
(1900 4675);
PAINT SKYBLUE (1900 4675);
DISPLAY INVISIBLE (1900 4675);
FORCEPROP 1 LAST BODY_TYPE PLUMBING
J 0
(1855 4632);
DISPLAY 0.340426 (1855 4632);
PAINT GREEN (1855 4632);
DISPLAY INVISIBLE (1855 4632);
FORCEPROP 1 LAST HDL_POWER GND
J 0
(1900 4825);
DISPLAY 2.361702 (1900 4825);
PAINT GREEN (1900 4825);
DISPLAY INVISIBLE (1900 4825);
FORCEADD OFFPAGE..2
(2625 2150);
FORCEPROP 2 LAST $XR5 82 
J 0
(3264 2150);
DISPLAY 0.638298 (3264 2150);
PAINT MONO (3264 2150);
FORCEPROP 2 LAST $XR4 81 
J 0
(3174 2150);
DISPLAY 0.638298 (3174 2150);
PAINT MONO (3174 2150);
FORCEPROP 2 LAST $XR3 80 
J 0
(3084 2150);
DISPLAY 0.638298 (3084 2150);
PAINT MONO (3084 2150);
FORCEPROP 2 LAST $XR2 79 
J 0
(2994 2150);
DISPLAY 0.638298 (2994 2150);
PAINT MONO (2994 2150);
FORCEPROP 2 LAST $XR1 78 
J 0
(2904 2150);
DISPLAY 0.638298 (2904 2150);
PAINT MONO (2904 2150);
FORCEPROP 2 LAST $XR0 77 
J 0
(2814 2150);
DISPLAY 0.638298 (2814 2150);
PAINT MONO (2814 2150);
FORCEPROP 2 LAST PATH I30
J 0
(2925 2200);
DISPLAY 1.021277 (2925 2200);
PAINT ORANGE (2925 2200);
DISPLAY INVISIBLE (2925 2200);
FORCEPROP 2 LAST BOM_COST SM_CONTROLLER
J 0
(2950 2200);
PAINT MONO (2950 2200);
DISPLAY INVISIBLE (2950 2200);
FORCEPROP 2 LAST CDS_LIB mstr_standard
J 0
(2625 2150);
PAINT ORANGE (2625 2150);
DISPLAY INVISIBLE (2625 2150);
FORCEPROP 1 LAST OFFPAGE TRUE
J 0
(2950 2025);
PAINT GREEN (2950 2025);
DISPLAY INVISIBLE (2950 2025);
FORCEPROP 1 LAST COMMENT_BODY TRUE
J 0
(2580 2055);
DISPLAY 0.872340 (2580 2055);
PAINT GREEN (2580 2055);
DISPLAY INVISIBLE (2580 2055);
FORCEADD PVPP_DEF..1
(1625 3950);
FORCEPROP 3 LASTPIN (1625 3900) SIG_NAME PVPP_DEF\g
J 0
(1635 3910);
DISPLAY 0.659574 (1635 3910);
PAINT MONO (1635 3910);
DISPLAY INVISIBLE (1635 3910);
FORCEPROP 1 LAST PATH I31
J 0
(1675 3975);
DISPLAY 0.872340 (1675 3975);
PAINT AQUA (1675 3975);
DISPLAY INVISIBLE (1675 3975);
FORCEPROP 2 LAST CDS_LIB mstr_symbols
J 0
(1625 3950);
PAINT ORANGE (1625 3950);
DISPLAY INVISIBLE (1625 3950);
FORCEPROP 1 LAST VOLTAGE 2.5V
J 0
(1580 3907);
DISPLAY 0.340426 (1580 3907);
PAINT SKYBLUE (1580 3907);
DISPLAY INVISIBLE (1580 3907);
FORCEPROP 1 LAST BODY_TYPE PLUMBING
J 0
(1580 3907);
DISPLAY 0.340426 (1580 3907);
PAINT GREEN (1580 3907);
DISPLAY INVISIBLE (1580 3907);
FORCEPROP 1 LAST HDL_POWER PVPP_DEF
J 1
(1625 4000);
DISPLAY 0.872340 (1625 4000);
PAINT GREEN (1625 4000);
DISPLAY INVISIBLE (1625 4000);
FORCEADD CAP_A..1
(1625 3750);
FORCEPROP 1 LASTPIN (1625 3650) $PN 2
J 0
(1635 3630);
DISPLAY 0.617021 (1635 3630);
PAINT MONO (1635 3630);
FORCEPROP 1 LASTPIN (1625 3850) $PN 1
J 0
(1635 3830);
DISPLAY 0.617021 (1635 3830);
PAINT MONO (1635 3830);
FORCEPROP 1 LAST MATERIAL X7R
J 0
(1675 3650);
DISPLAY 0.617021 (1675 3650);
PAINT SKYBLUE (1675 3650);
FORCEPROP 1 LAST VOLTAGE 16V
J 0
(1675 3750);
DISPLAY 0.617021 (1675 3750);
PAINT SKYBLUE (1675 3750);
FORCEPROP 1 LAST TOLERANCE 10%
J 0
(1675 3700);
DISPLAY 0.617021 (1675 3700);
PAINT SKYBLUE (1675 3700);
FORCEPROP 1 LAST VALUE 0.1UF
J 0
(1675 3800);
DISPLAY 0.617021 (1675 3800);
PAINT SKYBLUE (1675 3800);
FORCEPROP 1 LAST PART_NUMBER A36096-030
J 0
(1675 3600);
DISPLAY 0.617021 (1675 3600);
PAINT BLUE (1675 3600);
FORCEPROP 1 LAST LOCATION C7E2
J 0
(1675 3850);
DISPLAY 0.617021 (1675 3850);
PAINT AQUA (1675 3850);
FORCEPROP 1 LAST PACK_TYPE 0402V
J 0
(1675 3550);
DISPLAY 0.617021 (1675 3550);
PAINT SKYBLUE (1675 3550);
FORCEPROP 2 LAST $SEC 1
J 0
(1675 3950);
DISPLAY 0.936170 (1675 3950);
PAINT MONO (1675 3950);
DISPLAY INVISIBLE (1675 3950);
FORCEPROP 2 LAST CDS_SEC 1
J 0
(1675 3950);
DISPLAY 1.404255 (1675 3950);
PAINT ORANGE (1675 3950);
DISPLAY INVISIBLE (1675 3950);
FORCEPROP 2 LAST CDS_LIB dev_discrete
J 0
(1625 3750);
PAINT ORANGE (1625 3750);
DISPLAY INVISIBLE (1625 3750);
FORCEPROP 2 LAST BOM_COST SM_CONTROLLER
J 0
(1675 3900);
DISPLAY 2.170213 (1675 3900);
PAINT ORANGE (1675 3900);
DISPLAY INVISIBLE (1675 3900);
FORCEPROP 2 LAST SIGNAL_MODEL DEFAULT_CAPACITOR_100000pF_2_1
J 0
(1675 3975);
DISPLAY 1.617021 (1675 3975);
PAINT MONO (1675 3975);
DISPLAY INVISIBLE (1675 3975);
FORCEPROP 2 LAST CD_SEC 1
J 0
(1675 3975);
DISPLAY 1.617021 (1675 3975);
PAINT MONO (1675 3975);
DISPLAY INVISIBLE (1675 3975);
FORCEPROP 2 LAST CDS_LOCATION C7E2
J 0
(1675 3850);
DISPLAY 0.617021 (1675 3850);
PAINT AQUA (1675 3850);
DISPLAY INVISIBLE (1675 3850);
FORCEPROP 2 LAST ROOM MEM
J 0
(1675 3875);
PAINT MONO (1675 3875);
DISPLAY INVISIBLE (1675 3875);
FORCEPROP 1 LAST PATH I32
J 0
(1675 3900);
DISPLAY 0.978723 (1675 3900);
PAINT WHITE (1675 3900);
DISPLAY INVISIBLE (1675 3900);
FORCEADD GND..1
(1625 3500);
FORCEPROP 3 LASTPIN (1625 3550) SIG_NAME GND\g
J 0
(1635 3560);
DISPLAY 0.659574 (1635 3560);
PAINT MONO (1635 3560);
DISPLAY INVISIBLE (1635 3560);
FORCEPROP 2 LAST ROOM SMB
J 0
(1525 3575);
PAINT MONO (1525 3575);
DISPLAY INVISIBLE (1525 3575);
FORCEPROP 1 LAST PATH I33
J 0
(1700 3500);
DISPLAY 0.872340 (1700 3500);
PAINT AQUA (1700 3500);
DISPLAY INVISIBLE (1700 3500);
FORCEPROP 2 LAST CDS_LIB mstr_symbols
J 0
(1625 3500);
PAINT MONO (1625 3500);
DISPLAY INVISIBLE (1625 3500);
FORCEPROP 1 LAST SIZE 1B
J 0
(1700 3450);
DISPLAY 2.361702 (1700 3450);
PAINT GREEN (1700 3450);
DISPLAY INVISIBLE (1700 3450);
FORCEPROP 1 LAST VOLTAGE 0
J 0
(1625 3500);
PAINT SKYBLUE (1625 3500);
DISPLAY INVISIBLE (1625 3500);
FORCEPROP 1 LAST BODY_TYPE PLUMBING
J 0
(1580 3457);
DISPLAY 0.340426 (1580 3457);
PAINT GREEN (1580 3457);
DISPLAY INVISIBLE (1580 3457);
FORCEPROP 1 LAST HDL_POWER GND
J 0
(1625 3650);
DISPLAY 2.361702 (1625 3650);
PAINT GREEN (1625 3650);
DISPLAY INVISIBLE (1625 3650);
FORCEADD RES..1
(1600 3250);
FORCEPROP 1 LASTPIN (1500 3250) $PN 1
J 0
(1512 3262);
DISPLAY 0.617021 (1512 3262);
PAINT MONO (1512 3262);
FORCEPROP 1 LASTPIN (1700 3250) $PN 2
J 0
(1662 3262);
DISPLAY 0.617021 (1662 3262);
PAINT MONO (1662 3262);
FORCEPROP 1 LAST WATTAGE 1/16W
J 2
(2025 3150);
DISPLAY 0.617021 (2025 3150);
PAINT SKYBLUE (2025 3150);
FORCEPROP 1 LAST MATERIAL CHIP
J 0
(2050 3150);
DISPLAY 0.617021 (2050 3150);
PAINT SKYBLUE (2050 3150);
FORCEPROP 1 LAST PACK_TYPE 0402
J 0
(1650 3200);
DISPLAY 0.617021 (1650 3200);
PAINT SKYBLUE (1650 3200);
FORCEPROP 1 LAST TOLERANCE 1%
J 0
(1850 3200);
DISPLAY 0.617021 (1850 3200);
PAINT SKYBLUE (1850 3200);
FORCEPROP 1 LAST VALUE 20.0
J 2
(1550 3200);
DISPLAY 0.617021 (1550 3200);
PAINT SKYBLUE (1550 3200);
FORCEPROP 1 LAST PART_NUMBER G21796-173
J 0
(1875 3100);
DISPLAY 0.617021 (1875 3100);
PAINT BLUE (1875 3100);
FORCEPROP 1 LAST LOCATION R3R9
J 0
(1300 3200);
DISPLAY 0.617021 (1300 3200);
PAINT AQUA (1300 3200);
FORCEPROP 2 LASTPIN (1700 3250) SIG_NAME SMB_DDR_DEF_VPP_SDA
J 0
(1890 3260);
DISPLAY 0.617021 (1890 3260);
PAINT ORANGE (1890 3260);
FORCEPROP 2 LAST ROOM MEM
J 0
(1800 3250);
DISPLAY 1.404255 (1800 3250);
PAINT ORANGE (1800 3250);
DISPLAY INVISIBLE (1800 3250);
FORCEPROP 1 LAST PATH I34
J 0
(1550 3400);
DISPLAY 0.978723 (1550 3400);
PAINT WHITE (1550 3400);
DISPLAY INVISIBLE (1550 3400);
FORCEPROP 2 LAST CDS_LOCATION R3R9
J 0
(1300 3200);
DISPLAY 0.617021 (1300 3200);
PAINT AQUA (1300 3200);
DISPLAY INVISIBLE (1300 3200);
FORCEPROP 2 LAST $SEC 1
J 0
(1550 3450);
DISPLAY 0.936170 (1550 3450);
PAINT MONO (1550 3450);
DISPLAY INVISIBLE (1550 3450);
FORCEPROP 2 LAST CDS_SEC 1
J 0
(1550 3450);
DISPLAY 1.404255 (1550 3450);
PAINT ORANGE (1550 3450);
DISPLAY INVISIBLE (1550 3450);
FORCEPROP 2 LAST CDS_LIB mstr_discrete
J 0
(1600 3250);
PAINT ORANGE (1600 3250);
DISPLAY INVISIBLE (1600 3250);
FORCEADD RES..1
(1600 3300);
FORCEPROP 1 LASTPIN (1500 3300) $PN 1
J 0
(1512 3312);
DISPLAY 0.617021 (1512 3312);
PAINT MONO (1512 3312);
FORCEPROP 1 LASTPIN (1700 3300) $PN 2
J 0
(1662 3312);
DISPLAY 0.617021 (1662 3312);
PAINT MONO (1662 3312);
FORCEPROP 1 LAST WATTAGE 1/16W
J 2
(2000 3400);
DISPLAY 0.617021 (2000 3400);
PAINT SKYBLUE (2000 3400);
FORCEPROP 1 LAST MATERIAL CHIP
J 0
(2025 3400);
DISPLAY 0.617021 (2025 3400);
PAINT SKYBLUE (2025 3400);
FORCEPROP 1 LAST PACK_TYPE 0402
J 0
(1650 3350);
DISPLAY 0.617021 (1650 3350);
PAINT SKYBLUE (1650 3350);
FORCEPROP 1 LAST TOLERANCE 1%
J 0
(1850 3350);
DISPLAY 0.617021 (1850 3350);
PAINT SKYBLUE (1850 3350);
FORCEPROP 1 LAST VALUE 20.0
J 2
(1550 3350);
DISPLAY 0.617021 (1550 3350);
PAINT SKYBLUE (1550 3350);
FORCEPROP 1 LAST PART_NUMBER G21796-173
J 0
(1850 3450);
DISPLAY 0.617021 (1850 3450);
PAINT BLUE (1850 3450);
FORCEPROP 1 LAST LOCATION R3R8
J 0
(1550 3375);
DISPLAY 0.617021 (1550 3375);
PAINT AQUA (1550 3375);
FORCEPROP 2 LAST ROOM MEM
J 0
(1800 3400);
DISPLAY 1.404255 (1800 3400);
PAINT ORANGE (1800 3400);
DISPLAY INVISIBLE (1800 3400);
FORCEPROP 1 LAST PATH I35
J 0
(1550 3450);
DISPLAY 0.978723 (1550 3450);
PAINT WHITE (1550 3450);
DISPLAY INVISIBLE (1550 3450);
FORCEPROP 2 LAST CDS_LOCATION R3R8
J 0
(1550 3375);
DISPLAY 0.617021 (1550 3375);
PAINT AQUA (1550 3375);
DISPLAY INVISIBLE (1550 3375);
FORCEPROP 2 LAST $SEC 1
J 0
(1550 3500);
DISPLAY 0.936170 (1550 3500);
PAINT MONO (1550 3500);
DISPLAY INVISIBLE (1550 3500);
FORCEPROP 2 LAST CDS_SEC 1
J 0
(1550 3500);
DISPLAY 1.404255 (1550 3500);
PAINT ORANGE (1550 3500);
DISPLAY INVISIBLE (1550 3500);
FORCEPROP 2 LAST CDS_LIB mstr_discrete
J 0
(1600 3300);
PAINT ORANGE (1600 3300);
DISPLAY INVISIBLE (1600 3300);
FORCEADD PVPP_GHJ..1
(1650 2875);
FORCEPROP 3 LASTPIN (1650 2825) SIG_NAME PVPP_GHJ\g
J 0
(1660 2835);
DISPLAY 0.659574 (1660 2835);
PAINT MONO (1660 2835);
DISPLAY INVISIBLE (1660 2835);
FORCEPROP 2 LAST ROOM SMB
J 0
(1650 2950);
PAINT MONO (1650 2950);
DISPLAY INVISIBLE (1650 2950);
FORCEPROP 1 LAST PATH I39
J 0
(1700 2900);
DISPLAY 0.872340 (1700 2900);
PAINT AQUA (1700 2900);
DISPLAY INVISIBLE (1700 2900);
FORCEPROP 2 LAST CDS_LIB mstr_symbols
J 0
(1650 2875);
PAINT ORANGE (1650 2875);
DISPLAY INVISIBLE (1650 2875);
FORCEPROP 2 LAST BOM_COST SM_CONTROLLER
J 0
(1650 2975);
DISPLAY 1.617021 (1650 2975);
PAINT ORANGE (1650 2975);
DISPLAY INVISIBLE (1650 2975);
FORCEPROP 1 LAST VOLTAGE 2.5V
J 0
(1605 2832);
DISPLAY 0.340426 (1605 2832);
PAINT SKYBLUE (1605 2832);
DISPLAY INVISIBLE (1605 2832);
FORCEPROP 1 LAST BODY_TYPE PLUMBING
J 0
(1605 2832);
DISPLAY 0.340426 (1605 2832);
PAINT GREEN (1605 2832);
DISPLAY INVISIBLE (1605 2832);
FORCEPROP 1 LAST HDL_POWER PVPP_GHJ
J 1
(1650 2925);
DISPLAY 0.872340 (1650 2925);
PAINT GREEN (1650 2925);
DISPLAY INVISIBLE (1650 2925);
FORCEADD OFFPAGE..2
(2600 4350);
FORCEPROP 2 LAST $XR5 48 
J 0
(3239 4350);
DISPLAY 0.638298 (3239 4350);
PAINT MONO (3239 4350);
FORCEPROP 2 LAST $XR4 47 
J 0
(3149 4350);
DISPLAY 0.638298 (3149 4350);
PAINT MONO (3149 4350);
FORCEPROP 2 LAST $XR3 46 
J 0
(3059 4350);
DISPLAY 0.638298 (3059 4350);
PAINT MONO (3059 4350);
FORCEPROP 2 LAST $XR2 45 
J 0
(2969 4350);
DISPLAY 0.638298 (2969 4350);
PAINT MONO (2969 4350);
FORCEPROP 2 LAST $XR1 44 
J 0
(2879 4350);
DISPLAY 0.638298 (2879 4350);
PAINT MONO (2879 4350);
FORCEPROP 2 LAST $XR0 43 
J 0
(2789 4350);
DISPLAY 0.638298 (2789 4350);
PAINT MONO (2789 4350);
FORCEPROP 2 LAST PATH I4
J 0
(2900 4400);
DISPLAY 1.021277 (2900 4400);
PAINT ORANGE (2900 4400);
DISPLAY INVISIBLE (2900 4400);
FORCEPROP 2 LAST BOM_COST SM_CONTROLLER
J 0
(2925 4400);
PAINT MONO (2925 4400);
DISPLAY INVISIBLE (2925 4400);
FORCEPROP 2 LAST CDS_LIB mstr_standard
J 0
(2600 4350);
PAINT ORANGE (2600 4350);
DISPLAY INVISIBLE (2600 4350);
FORCEPROP 1 LAST OFFPAGE TRUE
J 0
(2925 4225);
PAINT GREEN (2925 4225);
DISPLAY INVISIBLE (2925 4225);
FORCEPROP 1 LAST COMMENT_BODY TRUE
J 0
(2555 4255);
DISPLAY 0.872340 (2555 4255);
PAINT GREEN (2555 4255);
DISPLAY INVISIBLE (2555 4255);
FORCEADD GND..1
(1650 2425);
FORCEPROP 3 LASTPIN (1650 2475) SIG_NAME GND\g
J 0
(1660 2485);
DISPLAY 0.659574 (1660 2485);
PAINT MONO (1660 2485);
DISPLAY INVISIBLE (1660 2485);
FORCEPROP 2 LAST ROOM SMB
J 0
(1550 2500);
PAINT MONO (1550 2500);
DISPLAY INVISIBLE (1550 2500);
FORCEPROP 1 LAST PATH I40
J 0
(1725 2425);
DISPLAY 0.872340 (1725 2425);
PAINT AQUA (1725 2425);
DISPLAY INVISIBLE (1725 2425);
FORCEPROP 2 LAST BOM_COST SM_CONTROLLER
J 0
(1250 2500);
DISPLAY 1.617021 (1250 2500);
PAINT ORANGE (1250 2500);
DISPLAY INVISIBLE (1250 2500);
FORCEPROP 2 LAST CDS_LIB mstr_symbols
J 0
(1650 2425);
PAINT MONO (1650 2425);
DISPLAY INVISIBLE (1650 2425);
FORCEPROP 1 LAST SIZE 1B
J 0
(1725 2375);
DISPLAY 2.361702 (1725 2375);
PAINT GREEN (1725 2375);
DISPLAY INVISIBLE (1725 2375);
FORCEPROP 1 LAST VOLTAGE 0
J 0
(1650 2425);
PAINT SKYBLUE (1650 2425);
DISPLAY INVISIBLE (1650 2425);
FORCEPROP 1 LAST BODY_TYPE PLUMBING
J 0
(1605 2382);
DISPLAY 0.340426 (1605 2382);
PAINT GREEN (1605 2382);
DISPLAY INVISIBLE (1605 2382);
FORCEPROP 1 LAST HDL_POWER GND
J 0
(1650 2575);
DISPLAY 2.361702 (1650 2575);
PAINT GREEN (1650 2575);
DISPLAY INVISIBLE (1650 2575);
FORCEADD CAP_A..1
(1650 2675);
FORCEPROP 1 LASTPIN (1650 2575) $PN 2
J 0
(1660 2555);
DISPLAY 0.617021 (1660 2555);
PAINT MONO (1660 2555);
FORCEPROP 1 LASTPIN (1650 2775) $PN 1
J 0
(1660 2755);
DISPLAY 0.617021 (1660 2755);
PAINT MONO (1660 2755);
FORCEPROP 1 LAST PACK_TYPE 0402V
J 0
(1700 2475);
DISPLAY 0.617021 (1700 2475);
PAINT SKYBLUE (1700 2475);
FORCEPROP 1 LAST TOLERANCE 10%
J 0
(1700 2625);
DISPLAY 0.617021 (1700 2625);
PAINT SKYBLUE (1700 2625);
FORCEPROP 1 LAST VOLTAGE 16V
J 0
(1700 2675);
DISPLAY 0.617021 (1700 2675);
PAINT SKYBLUE (1700 2675);
FORCEPROP 1 LAST PART_NUMBER A36096-030
J 0
(1700 2525);
DISPLAY 0.617021 (1700 2525);
PAINT BLUE (1700 2525);
FORCEPROP 1 LAST MATERIAL X7R
J 0
(1700 2575);
DISPLAY 0.617021 (1700 2575);
PAINT SKYBLUE (1700 2575);
FORCEPROP 1 LAST VALUE 0.1UF
J 0
(1700 2725);
DISPLAY 0.617021 (1700 2725);
PAINT SKYBLUE (1700 2725);
FORCEPROP 1 LAST LOCATION C4G25
J 0
(1700 2775);
DISPLAY 0.617021 (1700 2775);
PAINT AQUA (1700 2775);
FORCEPROP 2 LAST $SEC 1
J 0
(1700 2875);
DISPLAY 0.936170 (1700 2875);
PAINT MONO (1700 2875);
DISPLAY INVISIBLE (1700 2875);
FORCEPROP 2 LAST CDS_SEC 1
J 0
(1700 2875);
DISPLAY 1.404255 (1700 2875);
PAINT ORANGE (1700 2875);
DISPLAY INVISIBLE (1700 2875);
FORCEPROP 2 LAST CDS_LIB dev_discrete
J 0
(1650 2675);
PAINT ORANGE (1650 2675);
DISPLAY INVISIBLE (1650 2675);
FORCEPROP 2 LAST CD_SEC 1
J 0
(1700 2900);
DISPLAY 1.617021 (1700 2900);
PAINT MONO (1700 2900);
DISPLAY INVISIBLE (1700 2900);
FORCEPROP 2 LAST SIGNAL_MODEL DEFAULT_CAPACITOR_100000pF_2_1
J 0
(1700 2900);
DISPLAY 1.617021 (1700 2900);
PAINT MONO (1700 2900);
DISPLAY INVISIBLE (1700 2900);
FORCEPROP 2 LAST BOM_COST SM_CONTROLLER
J 0
(1700 2825);
DISPLAY 2.170213 (1700 2825);
PAINT ORANGE (1700 2825);
DISPLAY INVISIBLE (1700 2825);
FORCEPROP 2 LAST CDS_LOCATION C4G25
J 0
(1700 2775);
DISPLAY 0.617021 (1700 2775);
PAINT AQUA (1700 2775);
DISPLAY INVISIBLE (1700 2775);
FORCEPROP 2 LAST ROOM MEM
J 0
(1700 2800);
PAINT MONO (1700 2800);
DISPLAY INVISIBLE (1700 2800);
FORCEPROP 1 LAST PATH I41
J 0
(1700 2825);
DISPLAY 0.978723 (1700 2825);
PAINT WHITE (1700 2825);
DISPLAY INVISIBLE (1700 2825);
FORCEADD RES..1
(1600 2150);
FORCEPROP 1 LAST PART_NUMBER G21796-173
J 0
(1825 2300);
DISPLAY 0.617021 (1825 2300);
PAINT BLUE (1825 2300);
FORCEPROP 1 LAST PACK_TYPE 0402
J 0
(1650 2200);
DISPLAY 0.617021 (1650 2200);
PAINT SKYBLUE (1650 2200);
FORCEPROP 1 LAST WATTAGE 1/16W
J 2
(1975 2250);
DISPLAY 0.617021 (1975 2250);
PAINT SKYBLUE (1975 2250);
FORCEPROP 1 LAST TOLERANCE 1%
J 0
(1850 2200);
DISPLAY 0.617021 (1850 2200);
PAINT SKYBLUE (1850 2200);
FORCEPROP 1 LASTPIN (1500 2150) $PN 1
J 0
(1512 2162);
DISPLAY 0.617021 (1512 2162);
PAINT MONO (1512 2162);
FORCEPROP 1 LAST MATERIAL CHIP
J 0
(2000 2250);
DISPLAY 0.617021 (2000 2250);
PAINT SKYBLUE (2000 2250);
FORCEPROP 1 LAST VALUE 20.0
J 2
(1550 2200);
DISPLAY 0.617021 (1550 2200);
PAINT SKYBLUE (1550 2200);
FORCEPROP 1 LASTPIN (1700 2150) $PN 2
J 0
(1662 2162);
DISPLAY 0.617021 (1662 2162);
PAINT MONO (1662 2162);
FORCEPROP 1 LAST LOCATION R6U13
J 0
(1550 2225);
DISPLAY 0.617021 (1550 2225);
PAINT AQUA (1550 2225);
FORCEPROP 1 LAST PATH I42
J 0
(1550 2300);
DISPLAY 0.978723 (1550 2300);
PAINT WHITE (1550 2300);
DISPLAY INVISIBLE (1550 2300);
FORCEPROP 2 LAST ROOM MEM
J 0
(1800 2250);
DISPLAY 1.404255 (1800 2250);
PAINT ORANGE (1800 2250);
DISPLAY INVISIBLE (1800 2250);
FORCEPROP 2 LAST CDS_LOCATION R6U13
J 0
(1550 2225);
DISPLAY 0.617021 (1550 2225);
PAINT AQUA (1550 2225);
DISPLAY INVISIBLE (1550 2225);
FORCEPROP 2 LAST $SEC 1
J 0
(1550 2350);
DISPLAY 0.936170 (1550 2350);
PAINT MONO (1550 2350);
DISPLAY INVISIBLE (1550 2350);
FORCEPROP 2 LAST CDS_SEC 1
J 0
(1550 2350);
DISPLAY 1.404255 (1550 2350);
PAINT ORANGE (1550 2350);
DISPLAY INVISIBLE (1550 2350);
FORCEPROP 2 LAST CDS_LIB mstr_discrete
J 0
(1600 2150);
PAINT ORANGE (1600 2150);
DISPLAY INVISIBLE (1600 2150);
FORCEADD CAP_A..1
(2250 1525);
FORCEPROP 1 LASTPIN (2250 1625) $PN 1
J 0
(2260 1605);
DISPLAY 0.617021 (2260 1605);
PAINT MONO (2260 1605);
FORCEPROP 1 LAST VALUE 0.1UF
J 0
(2300 1575);
DISPLAY 0.617021 (2300 1575);
PAINT SKYBLUE (2300 1575);
FORCEPROP 1 LASTPIN (2250 1425) $PN 2
J 0
(2260 1405);
DISPLAY 0.617021 (2260 1405);
PAINT MONO (2260 1405);
FORCEPROP 1 LAST MATERIAL X7R
J 0
(2300 1425);
DISPLAY 0.617021 (2300 1425);
PAINT SKYBLUE (2300 1425);
FORCEPROP 1 LAST VOLTAGE 16V
J 0
(2300 1525);
DISPLAY 0.617021 (2300 1525);
PAINT SKYBLUE (2300 1525);
FORCEPROP 1 LAST TOLERANCE 10%
J 0
(2300 1475);
DISPLAY 0.617021 (2300 1475);
PAINT SKYBLUE (2300 1475);
FORCEPROP 1 LAST LOCATION C3B4
J 0
(2300 1625);
DISPLAY 0.617021 (2300 1625);
PAINT AQUA (2300 1625);
FORCEPROP 1 LAST PART_NUMBER A36096-030
J 0
(2300 1375);
DISPLAY 0.617021 (2300 1375);
PAINT BLUE (2300 1375);
FORCEPROP 1 LAST PACK_TYPE 0402V
J 0
(2300 1325);
DISPLAY 0.617021 (2300 1325);
PAINT SKYBLUE (2300 1325);
FORCEPROP 2 LAST $SEC 1
J 0
(2300 1725);
DISPLAY 0.936170 (2300 1725);
PAINT MONO (2300 1725);
DISPLAY INVISIBLE (2300 1725);
FORCEPROP 2 LAST CDS_SEC 1
J 0
(2300 1725);
DISPLAY 1.404255 (2300 1725);
PAINT ORANGE (2300 1725);
DISPLAY INVISIBLE (2300 1725);
FORCEPROP 2 LAST CDS_LIB dev_discrete
J 0
(2250 1525);
PAINT ORANGE (2250 1525);
DISPLAY INVISIBLE (2250 1525);
FORCEPROP 2 LAST BOM_COST SM_CONTROLLER
J 0
(2300 1675);
DISPLAY 2.170213 (2300 1675);
PAINT ORANGE (2300 1675);
DISPLAY INVISIBLE (2300 1675);
FORCEPROP 2 LAST SIGNAL_MODEL DEFAULT_CAPACITOR_100000pF_2_1
J 0
(2300 1750);
DISPLAY 1.617021 (2300 1750);
PAINT MONO (2300 1750);
DISPLAY INVISIBLE (2300 1750);
FORCEPROP 2 LAST CD_SEC 1
J 0
(2300 1750);
DISPLAY 1.617021 (2300 1750);
PAINT MONO (2300 1750);
DISPLAY INVISIBLE (2300 1750);
FORCEPROP 2 LAST CDS_LOCATION C3B4
J 0
(2300 1625);
DISPLAY 0.617021 (2300 1625);
PAINT AQUA (2300 1625);
DISPLAY INVISIBLE (2300 1625);
FORCEPROP 2 LAST ROOM MEM
J 0
(2300 1650);
PAINT MONO (2300 1650);
DISPLAY INVISIBLE (2300 1650);
FORCEPROP 1 LAST PATH I47
J 0
(2300 1675);
DISPLAY 0.978723 (2300 1675);
PAINT WHITE (2300 1675);
DISPLAY INVISIBLE (2300 1675);
FORCEADD PVCCIO_CPU1..1
(2250 1700);
FORCEPROP 3 LASTPIN (2250 1650) SIG_NAME PVCCIO_CPU1\g
J 0
(2260 1660);
DISPLAY 0.659574 (2260 1660);
PAINT MONO (2260 1660);
DISPLAY INVISIBLE (2260 1660);
FORCEPROP 1 LAST PATH I48
J 0
(2300 1725);
DISPLAY 0.872340 (2300 1725);
PAINT AQUA (2300 1725);
DISPLAY INVISIBLE (2300 1725);
FORCEPROP 2 LAST CDS_LIB mstr_symbols
J 0
(2250 1700);
PAINT ORANGE (2250 1700);
DISPLAY INVISIBLE (2250 1700);
FORCEPROP 1 LAST VOLTAGE 1.1V
J 0
(2205 1657);
DISPLAY 0.340426 (2205 1657);
PAINT SKYBLUE (2205 1657);
DISPLAY INVISIBLE (2205 1657);
FORCEPROP 1 LAST BODY_TYPE PLUMBING
J 0
(2205 1657);
DISPLAY 0.340426 (2205 1657);
PAINT GREEN (2205 1657);
DISPLAY INVISIBLE (2205 1657);
FORCEPROP 1 LAST HDL_POWER PVCCIO_CPU1
J 1
(2250 1750);
DISPLAY 0.872340 (2250 1750);
PAINT GREEN (2250 1750);
DISPLAY INVISIBLE (2250 1750);
FORCEADD GND..1
(2250 1275);
FORCEPROP 3 LASTPIN (2250 1325) SIG_NAME GND\g
J 0
(2260 1335);
DISPLAY 0.659574 (2260 1335);
PAINT MONO (2260 1335);
DISPLAY INVISIBLE (2260 1335);
FORCEPROP 2 LAST ROOM SMB
J 0
(2150 1350);
PAINT MONO (2150 1350);
DISPLAY INVISIBLE (2150 1350);
FORCEPROP 1 LAST PATH I49
J 0
(2325 1275);
DISPLAY 0.872340 (2325 1275);
PAINT AQUA (2325 1275);
DISPLAY INVISIBLE (2325 1275);
FORCEPROP 1 LAST SIZE 1B
J 0
(2325 1225);
DISPLAY 2.361702 (2325 1225);
PAINT GREEN (2325 1225);
DISPLAY INVISIBLE (2325 1225);
FORCEPROP 2 LAST CDS_LIB mstr_symbols
J 0
(2250 1275);
PAINT MONO (2250 1275);
DISPLAY INVISIBLE (2250 1275);
FORCEPROP 2 LAST BOM_COST SM_CONTROLLER
J 0
(1850 1350);
DISPLAY 1.617021 (1850 1350);
PAINT ORANGE (1850 1350);
DISPLAY INVISIBLE (1850 1350);
FORCEPROP 1 LAST VOLTAGE 0
J 0
(2250 1275);
PAINT SKYBLUE (2250 1275);
DISPLAY INVISIBLE (2250 1275);
FORCEPROP 1 LAST BODY_TYPE PLUMBING
J 0
(2205 1232);
DISPLAY 0.340426 (2205 1232);
PAINT GREEN (2205 1232);
DISPLAY INVISIBLE (2205 1232);
FORCEPROP 1 LAST HDL_POWER GND
J 0
(2250 1425);
DISPLAY 2.361702 (2250 1425);
PAINT GREEN (2250 1425);
DISPLAY INVISIBLE (2250 1425);
FORCEADD OFFPAGE..3
(2600 4300);
FORCEPROP 2 LAST $XR5 48 
J 0
(3264 4300);
DISPLAY 0.638298 (3264 4300);
PAINT MONO (3264 4300);
FORCEPROP 2 LAST $XR4 47 
J 0
(3174 4300);
DISPLAY 0.638298 (3174 4300);
PAINT MONO (3174 4300);
FORCEPROP 2 LAST $XR3 46 
J 0
(3084 4300);
DISPLAY 0.638298 (3084 4300);
PAINT MONO (3084 4300);
FORCEPROP 2 LAST $XR2 45 
J 0
(2994 4300);
DISPLAY 0.638298 (2994 4300);
PAINT MONO (2994 4300);
FORCEPROP 2 LAST $XR1 44 
J 0
(2904 4300);
DISPLAY 0.638298 (2904 4300);
PAINT MONO (2904 4300);
FORCEPROP 2 LAST $XR0 43 
J 0
(2814 4300);
DISPLAY 0.638298 (2814 4300);
PAINT MONO (2814 4300);
FORCEPROP 2 LAST PATH I5
J 0
(2925 4350);
DISPLAY 1.021277 (2925 4350);
PAINT ORANGE (2925 4350);
DISPLAY INVISIBLE (2925 4350);
FORCEPROP 2 LAST ROOM SMB
J 0
(3375 4350);
PAINT MONO (3375 4350);
DISPLAY INVISIBLE (3375 4350);
FORCEPROP 2 LAST CDS_LIB mstr_standard
J 0
(2600 4300);
PAINT MONO (2600 4300);
DISPLAY INVISIBLE (2600 4300);
FORCEPROP 2 LAST BOM_COST SM_CONTROLLER
J 0
(3375 4350);
PAINT MONO (3375 4350);
DISPLAY INVISIBLE (3375 4350);
FORCEPROP 1 LAST OFFPAGE TRUE
J 0
(2925 4175);
PAINT GREEN (2925 4175);
DISPLAY INVISIBLE (2925 4175);
FORCEPROP 1 LAST COMMENT_BODY TRUE
J 0
(2550 4200);
DISPLAY 1.872340 (2550 4200);
PAINT GREEN (2550 4200);
DISPLAY INVISIBLE (2550 4200);
FORCEADD OFFPAGE..2
(2625 950);
FORCEPROP 2 LAST $XR5 88 
J 0
(3264 950);
DISPLAY 0.638298 (3264 950);
PAINT MONO (3264 950);
FORCEPROP 2 LAST $XR4 87 
J 0
(3174 950);
DISPLAY 0.638298 (3174 950);
PAINT MONO (3174 950);
FORCEPROP 2 LAST $XR3 86 
J 0
(3084 950);
DISPLAY 0.638298 (3084 950);
PAINT MONO (3084 950);
FORCEPROP 2 LAST $XR2 85 
J 0
(2994 950);
DISPLAY 0.638298 (2994 950);
PAINT MONO (2994 950);
FORCEPROP 2 LAST $XR1 84 
J 0
(2904 950);
DISPLAY 0.638298 (2904 950);
PAINT MONO (2904 950);
FORCEPROP 2 LAST $XR0 83 
J 0
(2814 950);
DISPLAY 0.638298 (2814 950);
PAINT MONO (2814 950);
FORCEPROP 2 LAST PATH I50
J 0
(2925 1000);
DISPLAY 1.021277 (2925 1000);
PAINT ORANGE (2925 1000);
DISPLAY INVISIBLE (2925 1000);
FORCEPROP 2 LAST BOM_COST SM_CONTROLLER
J 0
(2950 1000);
PAINT MONO (2950 1000);
DISPLAY INVISIBLE (2950 1000);
FORCEPROP 2 LAST CDS_LIB mstr_standard
J 0
(2625 950);
PAINT ORANGE (2625 950);
DISPLAY INVISIBLE (2625 950);
FORCEPROP 1 LAST OFFPAGE TRUE
J 0
(2950 825);
PAINT GREEN (2950 825);
DISPLAY INVISIBLE (2950 825);
FORCEPROP 1 LAST COMMENT_BODY TRUE
J 0
(2580 855);
DISPLAY 0.872340 (2580 855);
PAINT GREEN (2580 855);
DISPLAY INVISIBLE (2580 855);
FORCEADD OFFPAGE..3
(2625 900);
FORCEPROP 2 LAST $XR5 88 
J 0
(3289 900);
DISPLAY 0.638298 (3289 900);
PAINT MONO (3289 900);
FORCEPROP 2 LAST $XR4 87 
J 0
(3199 900);
DISPLAY 0.638298 (3199 900);
PAINT MONO (3199 900);
FORCEPROP 2 LAST $XR3 86 
J 0
(3109 900);
DISPLAY 0.638298 (3109 900);
PAINT MONO (3109 900);
FORCEPROP 2 LAST $XR2 85 
J 0
(3019 900);
DISPLAY 0.638298 (3019 900);
PAINT MONO (3019 900);
FORCEPROP 2 LAST $XR1 84 
J 0
(2929 900);
DISPLAY 0.638298 (2929 900);
PAINT MONO (2929 900);
FORCEPROP 2 LAST $XR0 83 
J 0
(2839 900);
DISPLAY 0.638298 (2839 900);
PAINT MONO (2839 900);
FORCEPROP 2 LAST PATH I51
J 0
(2950 950);
DISPLAY 1.021277 (2950 950);
PAINT ORANGE (2950 950);
DISPLAY INVISIBLE (2950 950);
FORCEPROP 2 LAST ROOM SMB
J 0
(3300 950);
PAINT MONO (3300 950);
DISPLAY INVISIBLE (3300 950);
FORCEPROP 2 LAST BOM_COST SM_CONTROLLER
J 0
(3300 950);
PAINT MONO (3300 950);
DISPLAY INVISIBLE (3300 950);
FORCEPROP 2 LAST CDS_LIB mstr_standard
J 0
(2625 900);
PAINT MONO (2625 900);
DISPLAY INVISIBLE (2625 900);
FORCEPROP 1 LAST OFFPAGE TRUE
J 0
(2950 775);
PAINT GREEN (2950 775);
DISPLAY INVISIBLE (2950 775);
FORCEPROP 1 LAST COMMENT_BODY TRUE
J 0
(2575 800);
DISPLAY 1.872340 (2575 800);
PAINT GREEN (2575 800);
DISPLAY INVISIBLE (2575 800);
FORCEADD PVPP_KLM..1
(1675 1700);
FORCEPROP 3 LASTPIN (1675 1650) SIG_NAME PVPP_KLM\g
J 0
(1685 1660);
DISPLAY 0.659574 (1685 1660);
PAINT MONO (1685 1660);
DISPLAY INVISIBLE (1685 1660);
FORCEPROP 2 LAST ROOM SMB
J 0
(1675 1775);
PAINT MONO (1675 1775);
DISPLAY INVISIBLE (1675 1775);
FORCEPROP 1 LAST PATH I52
J 0
(1725 1725);
DISPLAY 0.872340 (1725 1725);
PAINT AQUA (1725 1725);
DISPLAY INVISIBLE (1725 1725);
FORCEPROP 2 LAST CDS_LIB mstr_symbols
J 0
(1675 1700);
PAINT ORANGE (1675 1700);
DISPLAY INVISIBLE (1675 1700);
FORCEPROP 2 LAST BOM_COST SM_CONTROLLER
J 0
(1675 1800);
DISPLAY 1.617021 (1675 1800);
PAINT ORANGE (1675 1800);
DISPLAY INVISIBLE (1675 1800);
FORCEPROP 1 LAST VOLTAGE 2.5V
J 0
(1630 1657);
DISPLAY 0.340426 (1630 1657);
PAINT SKYBLUE (1630 1657);
DISPLAY INVISIBLE (1630 1657);
FORCEPROP 1 LAST BODY_TYPE PLUMBING
J 0
(1630 1657);
DISPLAY 0.340426 (1630 1657);
PAINT GREEN (1630 1657);
DISPLAY INVISIBLE (1630 1657);
FORCEPROP 1 LAST HDL_POWER PVPP_KLM
J 1
(1675 1750);
DISPLAY 0.872340 (1675 1750);
PAINT GREEN (1675 1750);
DISPLAY INVISIBLE (1675 1750);
FORCEADD CAP_A..1
(1675 1500);
FORCEPROP 1 LASTPIN (1675 1400) $PN 2
J 0
(1685 1380);
DISPLAY 0.617021 (1685 1380);
PAINT MONO (1685 1380);
FORCEPROP 1 LASTPIN (1675 1600) $PN 1
J 0
(1685 1580);
DISPLAY 0.617021 (1685 1580);
PAINT MONO (1685 1580);
FORCEPROP 1 LAST MATERIAL X7R
J 0
(1725 1400);
DISPLAY 0.617021 (1725 1400);
PAINT SKYBLUE (1725 1400);
FORCEPROP 1 LAST PACK_TYPE 0402V
J 0
(1725 1300);
DISPLAY 0.617021 (1725 1300);
PAINT SKYBLUE (1725 1300);
FORCEPROP 1 LAST VOLTAGE 16V
J 0
(1725 1500);
DISPLAY 0.617021 (1725 1500);
PAINT SKYBLUE (1725 1500);
FORCEPROP 1 LAST TOLERANCE 10%
J 0
(1725 1450);
DISPLAY 0.617021 (1725 1450);
PAINT SKYBLUE (1725 1450);
FORCEPROP 1 LAST PART_NUMBER A36096-030
J 0
(1725 1350);
DISPLAY 0.617021 (1725 1350);
PAINT BLUE (1725 1350);
FORCEPROP 1 LAST VALUE 0.1UF
J 0
(1725 1550);
DISPLAY 0.617021 (1725 1550);
PAINT SKYBLUE (1725 1550);
FORCEPROP 1 LAST LOCATION C3B5
J 0
(1725 1600);
DISPLAY 0.617021 (1725 1600);
PAINT AQUA (1725 1600);
FORCEPROP 2 LAST $SEC 1
J 0
(1725 1700);
DISPLAY 0.936170 (1725 1700);
PAINT MONO (1725 1700);
DISPLAY INVISIBLE (1725 1700);
FORCEPROP 2 LAST CDS_SEC 1
J 0
(1725 1700);
DISPLAY 1.404255 (1725 1700);
PAINT ORANGE (1725 1700);
DISPLAY INVISIBLE (1725 1700);
FORCEPROP 2 LAST CDS_LIB dev_discrete
J 0
(1675 1500);
PAINT ORANGE (1675 1500);
DISPLAY INVISIBLE (1675 1500);
FORCEPROP 2 LAST SIGNAL_MODEL DEFAULT_CAPACITOR_100000pF_2_1
J 0
(1725 1725);
DISPLAY 1.617021 (1725 1725);
PAINT MONO (1725 1725);
DISPLAY INVISIBLE (1725 1725);
FORCEPROP 2 LAST CD_SEC 1
J 0
(1725 1725);
DISPLAY 1.617021 (1725 1725);
PAINT MONO (1725 1725);
DISPLAY INVISIBLE (1725 1725);
FORCEPROP 2 LAST BOM_COST SM_CONTROLLER
J 0
(1725 1650);
DISPLAY 2.170213 (1725 1650);
PAINT ORANGE (1725 1650);
DISPLAY INVISIBLE (1725 1650);
FORCEPROP 2 LAST CDS_LOCATION C3B5
J 0
(1725 1600);
DISPLAY 0.617021 (1725 1600);
PAINT AQUA (1725 1600);
DISPLAY INVISIBLE (1725 1600);
FORCEPROP 2 LAST ROOM MEM
J 0
(1725 1625);
PAINT MONO (1725 1625);
DISPLAY INVISIBLE (1725 1625);
FORCEPROP 1 LAST PATH I53
J 0
(1725 1650);
DISPLAY 0.978723 (1725 1650);
PAINT WHITE (1725 1650);
DISPLAY INVISIBLE (1725 1650);
FORCEADD GND..1
(1675 1250);
FORCEPROP 3 LASTPIN (1675 1300) SIG_NAME GND\g
J 0
(1685 1310);
DISPLAY 0.659574 (1685 1310);
PAINT MONO (1685 1310);
DISPLAY INVISIBLE (1685 1310);
FORCEPROP 2 LAST ROOM SMB
J 0
(1575 1325);
PAINT MONO (1575 1325);
DISPLAY INVISIBLE (1575 1325);
FORCEPROP 1 LAST PATH I54
J 0
(1750 1250);
DISPLAY 0.872340 (1750 1250);
PAINT AQUA (1750 1250);
DISPLAY INVISIBLE (1750 1250);
FORCEPROP 2 LAST BOM_COST SM_CONTROLLER
J 0
(1275 1325);
DISPLAY 1.617021 (1275 1325);
PAINT ORANGE (1275 1325);
DISPLAY INVISIBLE (1275 1325);
FORCEPROP 1 LAST SIZE 1B
J 0
(1750 1200);
DISPLAY 2.361702 (1750 1200);
PAINT GREEN (1750 1200);
DISPLAY INVISIBLE (1750 1200);
FORCEPROP 2 LAST CDS_LIB mstr_symbols
J 0
(1675 1250);
PAINT MONO (1675 1250);
DISPLAY INVISIBLE (1675 1250);
FORCEPROP 1 LAST VOLTAGE 0
J 0
(1675 1250);
PAINT SKYBLUE (1675 1250);
DISPLAY INVISIBLE (1675 1250);
FORCEPROP 1 LAST BODY_TYPE PLUMBING
J 0
(1630 1207);
DISPLAY 0.340426 (1630 1207);
PAINT GREEN (1630 1207);
DISPLAY INVISIBLE (1630 1207);
FORCEPROP 1 LAST HDL_POWER GND
J 0
(1675 1400);
DISPLAY 2.361702 (1675 1400);
PAINT GREEN (1675 1400);
DISPLAY INVISIBLE (1675 1400);
FORCEADD RES..1
(1600 900);
FORCEPROP 1 LASTPIN (1500 900) $PN 1
J 0
(1512 912);
DISPLAY 0.617021 (1512 912);
PAINT MONO (1512 912);
FORCEPROP 1 LASTPIN (1700 900) $PN 2
J 0
(1662 912);
DISPLAY 0.617021 (1662 912);
PAINT MONO (1662 912);
FORCEPROP 1 LAST MATERIAL CHIP
J 0
(2000 800);
DISPLAY 0.617021 (2000 800);
PAINT SKYBLUE (2000 800);
FORCEPROP 1 LAST PACK_TYPE 0402
J 0
(1650 850);
DISPLAY 0.617021 (1650 850);
PAINT SKYBLUE (1650 850);
FORCEPROP 1 LAST VALUE 20.0
J 2
(1550 850);
DISPLAY 0.617021 (1550 850);
PAINT SKYBLUE (1550 850);
FORCEPROP 1 LAST LOCATION R7M5
J 0
(1300 850);
DISPLAY 0.617021 (1300 850);
PAINT AQUA (1300 850);
FORCEPROP 1 LAST TOLERANCE 1%
J 0
(1875 850);
DISPLAY 0.617021 (1875 850);
PAINT SKYBLUE (1875 850);
FORCEPROP 1 LAST PART_NUMBER G21796-173
J 0
(1825 750);
DISPLAY 0.617021 (1825 750);
PAINT BLUE (1825 750);
FORCEPROP 1 LAST WATTAGE 1/16W
J 2
(1950 800);
DISPLAY 0.617021 (1950 800);
PAINT SKYBLUE (1950 800);
FORCEPROP 2 LAST ROOM MEM
J 0
(1800 900);
DISPLAY 1.404255 (1800 900);
PAINT ORANGE (1800 900);
DISPLAY INVISIBLE (1800 900);
FORCEPROP 1 LAST PATH I55
J 0
(1550 1050);
DISPLAY 0.978723 (1550 1050);
PAINT WHITE (1550 1050);
DISPLAY INVISIBLE (1550 1050);
FORCEPROP 2 LAST CDS_LOCATION R7M5
J 0
(1300 850);
DISPLAY 0.617021 (1300 850);
PAINT AQUA (1300 850);
DISPLAY INVISIBLE (1300 850);
FORCEPROP 2 LAST $SEC 1
J 0
(1550 1100);
DISPLAY 0.936170 (1550 1100);
PAINT MONO (1550 1100);
DISPLAY INVISIBLE (1550 1100);
FORCEPROP 2 LAST CDS_SEC 1
J 0
(1550 1100);
DISPLAY 1.404255 (1550 1100);
PAINT ORANGE (1550 1100);
DISPLAY INVISIBLE (1550 1100);
FORCEPROP 2 LAST CDS_LIB mstr_discrete
J 0
(1600 900);
PAINT ORANGE (1600 900);
DISPLAY INVISIBLE (1600 900);
FORCEADD RES..1
(1600 950);
FORCEPROP 1 LASTPIN (1500 950) $PN 1
J 0
(1512 962);
DISPLAY 0.617021 (1512 962);
PAINT MONO (1512 962);
FORCEPROP 1 LAST MATERIAL CHIP
J 0
(2000 1050);
DISPLAY 0.617021 (2000 1050);
PAINT SKYBLUE (2000 1050);
FORCEPROP 1 LAST PART_NUMBER G21796-173
J 0
(1800 1100);
DISPLAY 0.617021 (1800 1100);
PAINT BLUE (1800 1100);
FORCEPROP 1 LAST TOLERANCE 1%
J 0
(1850 1000);
DISPLAY 0.617021 (1850 1000);
PAINT SKYBLUE (1850 1000);
FORCEPROP 1 LAST WATTAGE 1/16W
J 2
(1950 1050);
DISPLAY 0.617021 (1950 1050);
PAINT SKYBLUE (1950 1050);
FORCEPROP 1 LASTPIN (1700 950) $PN 2
J 0
(1662 962);
DISPLAY 0.617021 (1662 962);
PAINT MONO (1662 962);
FORCEPROP 1 LAST VALUE 20.0
J 2
(1550 1000);
DISPLAY 0.617021 (1550 1000);
PAINT SKYBLUE (1550 1000);
FORCEPROP 1 LAST LOCATION R7M4
J 0
(1550 1025);
DISPLAY 0.617021 (1550 1025);
PAINT AQUA (1550 1025);
FORCEPROP 1 LAST PACK_TYPE 0402
J 0
(1650 1000);
DISPLAY 0.617021 (1650 1000);
PAINT SKYBLUE (1650 1000);
FORCEPROP 2 LAST ROOM MEM
J 0
(1800 1050);
DISPLAY 1.404255 (1800 1050);
PAINT ORANGE (1800 1050);
DISPLAY INVISIBLE (1800 1050);
FORCEPROP 1 LAST PATH I56
J 0
(1550 1100);
DISPLAY 0.978723 (1550 1100);
PAINT WHITE (1550 1100);
DISPLAY INVISIBLE (1550 1100);
FORCEPROP 2 LAST CDS_LOCATION R7M4
J 0
(1550 1025);
DISPLAY 0.617021 (1550 1025);
PAINT AQUA (1550 1025);
DISPLAY INVISIBLE (1550 1025);
FORCEPROP 2 LAST $SEC 1
J 0
(1550 1150);
DISPLAY 0.936170 (1550 1150);
PAINT MONO (1550 1150);
DISPLAY INVISIBLE (1550 1150);
FORCEPROP 2 LAST CDS_SEC 1
J 0
(1550 1150);
DISPLAY 1.404255 (1550 1150);
PAINT ORANGE (1550 1150);
DISPLAY INVISIBLE (1550 1150);
FORCEPROP 2 LAST CDS_LIB mstr_discrete
J 0
(1600 950);
PAINT ORANGE (1600 950);
DISPLAY INVISIBLE (1600 950);
FORCEADD PVPP_DEF..1
(625 3575);
FORCEPROP 3 LASTPIN (625 3525) SIG_NAME PVPP_DEF\g
J 0
(635 3535);
DISPLAY 0.659574 (635 3535);
PAINT MONO (635 3535);
DISPLAY INVISIBLE (635 3535);
FORCEPROP 2 LAST ROOM SMB
J 0
(625 3650);
PAINT MONO (625 3650);
DISPLAY INVISIBLE (625 3650);
FORCEPROP 1 LAST PATH I60
J 0
(675 3600);
DISPLAY 0.872340 (675 3600);
PAINT AQUA (675 3600);
DISPLAY INVISIBLE (675 3600);
FORCEPROP 2 LAST CDS_LIB mstr_symbols
J 0
(625 3575);
PAINT ORANGE (625 3575);
DISPLAY INVISIBLE (625 3575);
FORCEPROP 2 LAST BOM_COST SM_CONTROLLER
J 0
(625 3675);
DISPLAY 1.617021 (625 3675);
PAINT ORANGE (625 3675);
DISPLAY INVISIBLE (625 3675);
FORCEPROP 1 LAST VOLTAGE 2.5V
J 0
(580 3532);
DISPLAY 0.340426 (580 3532);
PAINT SKYBLUE (580 3532);
DISPLAY INVISIBLE (580 3532);
FORCEPROP 1 LAST BODY_TYPE PLUMBING
J 0
(580 3532);
DISPLAY 0.340426 (580 3532);
PAINT GREEN (580 3532);
DISPLAY INVISIBLE (580 3532);
FORCEPROP 1 LAST HDL_POWER PVPP_DEF
J 1
(625 3625);
DISPLAY 0.872340 (625 3625);
PAINT GREEN (625 3625);
DISPLAY INVISIBLE (625 3625);
FORCEADD PCA9617..1
(150 3250);
FORCEPROP 2 LASTPIN (-250 3150) $PN 5
J 2
(-260 3160);
DISPLAY 0.617021 (-260 3160);
PAINT MONO (-260 3160);
FORCEPROP 2 LASTPIN (-250 3300) $PN 2
J 2
(-260 3310);
DISPLAY 0.617021 (-260 3310);
PAINT MONO (-260 3310);
FORCEPROP 2 LASTPIN (550 3300) $PN 7
J 0
(560 3310);
DISPLAY 0.617021 (560 3310);
PAINT MONO (560 3310);
FORCEPROP 2 LASTPIN (-250 3250) $PN 3
J 2
(-260 3260);
DISPLAY 0.617021 (-260 3260);
PAINT MONO (-260 3260);
FORCEPROP 2 LASTPIN (550 3250) $PN 6
J 0
(560 3260);
DISPLAY 0.617021 (560 3260);
PAINT MONO (560 3260);
FORCEPROP 2 LASTPIN (-250 3400) $PN 1
J 2
(-260 3410);
DISPLAY 0.617021 (-260 3410);
PAINT MONO (-260 3410);
FORCEPROP 2 LASTPIN (550 3400) $PN 8
J 0
(560 3410);
DISPLAY 0.617021 (560 3410);
PAINT MONO (560 3410);
FORCEPROP 1 LAST MATERIAL IC
J 0
(-200 3525);
DISPLAY 0.617021 (-200 3525);
PAINT SKYBLUE (-200 3525);
FORCEPROP 1 LAST PART_NUMBER G81764-001
J 0
(-200 3050);
DISPLAY 0.617021 (-200 3050);
PAINT BLUE (-200 3050);
FORCEPROP 1 LAST LOCATION U7E1
J 0
(-200 3575);
DISPLAY 0.617021 (-200 3575);
PAINT AQUA (-200 3575);
FORCEPROP 1 LAST POWER_GROUP GND=GND
J 0
(-200 3000);
DISPLAY 0.617021 (-200 3000);
PAINT ORANGE (-200 3000);
FORCEPROP 2 LAST ROOM MEM
J 0
(-200 3625);
PAINT MONO (-200 3625);
DISPLAY INVISIBLE (-200 3625);
FORCEPROP 1 LAST PATH I61
J 0
(275 3525);
PAINT GREEN (275 3525);
DISPLAY INVISIBLE (275 3525);
FORCEPROP 2 LAST CDS_LOCATION U7E1
J 0
(-200 3575);
DISPLAY 0.617021 (-200 3575);
PAINT AQUA (-200 3575);
DISPLAY INVISIBLE (-200 3575);
FORCEPROP 2 LAST $SEC 1
J 0
(-200 3625);
DISPLAY 0.936170 (-200 3625);
PAINT MONO (-200 3625);
DISPLAY INVISIBLE (-200 3625);
FORCEPROP 2 LAST CDS_SEC 1
J 0
(-200 3625);
DISPLAY 1.404255 (-200 3625);
PAINT ORANGE (-200 3625);
DISPLAY INVISIBLE (-200 3625);
FORCEPROP 2 LAST BOM_COST SM_CONTROLLER
J 0
(-200 3625);
PAINT MONO (-200 3625);
DISPLAY INVISIBLE (-200 3625);
FORCEPROP 2 LAST CDS_LIB mstr_digital
J 0
(150 3250);
PAINT MONO (150 3250);
DISPLAY INVISIBLE (150 3250);
FORCEPROP 1 LAST PACK_TYPE SSOP
J 0
(-200 3625);
PAINT SKYBLUE (-200 3625);
DISPLAY INVISIBLE (-200 3625);
FORCEADD PVPP_GHJ..1
(600 2425);
FORCEPROP 3 LASTPIN (600 2375) SIG_NAME PVPP_GHJ\g
J 0
(610 2385);
DISPLAY 0.659574 (610 2385);
PAINT MONO (610 2385);
DISPLAY INVISIBLE (610 2385);
FORCEPROP 2 LAST ROOM SMB
J 0
(600 2500);
PAINT MONO (600 2500);
DISPLAY INVISIBLE (600 2500);
FORCEPROP 1 LAST PATH I62
J 0
(650 2450);
DISPLAY 0.872340 (650 2450);
PAINT AQUA (650 2450);
DISPLAY INVISIBLE (650 2450);
FORCEPROP 2 LAST CDS_LIB mstr_symbols
J 0
(600 2425);
PAINT ORANGE (600 2425);
DISPLAY INVISIBLE (600 2425);
FORCEPROP 2 LAST BOM_COST SM_CONTROLLER
J 0
(600 2525);
DISPLAY 1.617021 (600 2525);
PAINT ORANGE (600 2525);
DISPLAY INVISIBLE (600 2525);
FORCEPROP 1 LAST VOLTAGE 2.5V
J 0
(555 2382);
DISPLAY 0.340426 (555 2382);
PAINT SKYBLUE (555 2382);
DISPLAY INVISIBLE (555 2382);
FORCEPROP 1 LAST BODY_TYPE PLUMBING
J 0
(555 2382);
DISPLAY 0.340426 (555 2382);
PAINT GREEN (555 2382);
DISPLAY INVISIBLE (555 2382);
FORCEPROP 1 LAST HDL_POWER PVPP_GHJ
J 1
(600 2475);
DISPLAY 0.872340 (600 2475);
PAINT GREEN (600 2475);
DISPLAY INVISIBLE (600 2475);
FORCEADD PCA9617..1
(150 2100);
FORCEPROP 2 LASTPIN (-250 2000) $PN 5
J 2
(-260 2010);
DISPLAY 0.617021 (-260 2010);
PAINT MONO (-260 2010);
FORCEPROP 2 LASTPIN (-250 2150) $PN 2
J 2
(-260 2160);
DISPLAY 0.617021 (-260 2160);
PAINT MONO (-260 2160);
FORCEPROP 2 LASTPIN (-250 2100) $PN 3
J 2
(-260 2110);
DISPLAY 0.617021 (-260 2110);
PAINT MONO (-260 2110);
FORCEPROP 2 LASTPIN (550 2100) $PN 6
J 0
(560 2110);
DISPLAY 0.617021 (560 2110);
PAINT MONO (560 2110);
FORCEPROP 2 LASTPIN (-250 2250) $PN 1
J 2
(-260 2260);
DISPLAY 0.617021 (-260 2260);
PAINT MONO (-260 2260);
FORCEPROP 1 LAST MATERIAL IC
J 0
(-200 2375);
DISPLAY 0.617021 (-200 2375);
PAINT SKYBLUE (-200 2375);
FORCEPROP 1 LAST PART_NUMBER G81764-001
J 0
(-200 1900);
DISPLAY 0.617021 (-200 1900);
PAINT BLUE (-200 1900);
FORCEPROP 1 LAST LOCATION U4G1
J 0
(-200 2425);
DISPLAY 0.617021 (-200 2425);
PAINT AQUA (-200 2425);
FORCEPROP 1 LAST POWER_GROUP GND=GND
J 0
(-200 1850);
DISPLAY 0.617021 (-200 1850);
PAINT ORANGE (-200 1850);
FORCEPROP 2 LASTPIN (550 2150) $PN 7
J 0
(560 2160);
DISPLAY 0.617021 (560 2160);
PAINT MONO (560 2160);
FORCEPROP 2 LASTPIN (550 2250) $PN 8
J 0
(560 2260);
DISPLAY 0.617021 (560 2260);
PAINT MONO (560 2260);
FORCEPROP 2 LAST ROOM MEM
J 0
(-200 2475);
PAINT MONO (-200 2475);
DISPLAY INVISIBLE (-200 2475);
FORCEPROP 1 LAST PATH I63
J 0
(275 2375);
PAINT GREEN (275 2375);
DISPLAY INVISIBLE (275 2375);
FORCEPROP 2 LAST CDS_LOCATION U4G1
J 0
(-200 2425);
DISPLAY 0.617021 (-200 2425);
PAINT AQUA (-200 2425);
DISPLAY INVISIBLE (-200 2425);
FORCEPROP 2 LAST $SEC 1
J 0
(-200 2475);
DISPLAY 0.936170 (-200 2475);
PAINT MONO (-200 2475);
DISPLAY INVISIBLE (-200 2475);
FORCEPROP 2 LAST CDS_SEC 1
J 0
(-200 2475);
DISPLAY 1.404255 (-200 2475);
PAINT ORANGE (-200 2475);
DISPLAY INVISIBLE (-200 2475);
FORCEPROP 2 LAST BOM_COST SM_CONTROLLER
J 0
(-200 2475);
PAINT MONO (-200 2475);
DISPLAY INVISIBLE (-200 2475);
FORCEPROP 2 LAST CDS_LIB mstr_digital
J 0
(150 2100);
PAINT MONO (150 2100);
DISPLAY INVISIBLE (150 2100);
FORCEPROP 1 LAST PACK_TYPE SSOP
J 0
(-200 2475);
PAINT SKYBLUE (-200 2475);
DISPLAY INVISIBLE (-200 2475);
FORCEADD PVCCIO_CPU0..1
(-500 3825);
FORCEPROP 3 LASTPIN (-500 3775) SIG_NAME PVCCIO_CPU0\g
J 0
(-490 3785);
DISPLAY 0.659574 (-490 3785);
PAINT MONO (-490 3785);
DISPLAY INVISIBLE (-490 3785);
FORCEPROP 1 LAST PATH I64
J 0
(-450 3850);
DISPLAY 0.872340 (-450 3850);
PAINT AQUA (-450 3850);
DISPLAY INVISIBLE (-450 3850);
FORCEPROP 2 LAST CDS_LIB mstr_symbols
J 0
(-500 3825);
PAINT ORANGE (-500 3825);
DISPLAY INVISIBLE (-500 3825);
FORCEPROP 1 LAST VOLTAGE 1.1V
J 0
(-545 3782);
DISPLAY 0.340426 (-545 3782);
PAINT SKYBLUE (-545 3782);
DISPLAY INVISIBLE (-545 3782);
FORCEPROP 1 LAST BODY_TYPE PLUMBING
J 0
(-545 3782);
DISPLAY 0.340426 (-545 3782);
PAINT GREEN (-545 3782);
DISPLAY INVISIBLE (-545 3782);
FORCEPROP 1 LAST HDL_POWER PVCCIO_CPU0
J 1
(-500 3875);
DISPLAY 0.872340 (-500 3875);
PAINT GREEN (-500 3875);
DISPLAY INVISIBLE (-500 3875);
FORCEADD RES..2
R 2
(-675 3600);
FORCEPROP 1 LASTPIN (-675 3700) $PN 1
J 2
(-680 3662);
DISPLAY 0.617021 (-680 3662);
PAINT MONO (-680 3662);
FORCEPROP 1 LASTPIN (-675 3500) $PN 2
J 2
(-680 3510);
DISPLAY 0.617021 (-680 3510);
PAINT MONO (-680 3510);
FORCEPROP 1 LAST WATTAGE 1/16W
J 2
(-715 3575);
DISPLAY 0.617021 (-715 3575);
PAINT SKYBLUE (-715 3575);
FORCEPROP 1 LAST MATERIAL CHIP
J 2
(-715 3525);
DISPLAY 0.617021 (-715 3525);
PAINT SKYBLUE (-715 3525);
FORCEPROP 1 LAST PACK_TYPE 0402
J 2
(-715 3425);
DISPLAY 0.617021 (-715 3425);
PAINT SKYBLUE (-715 3425);
FORCEPROP 1 LAST TOLERANCE 1.0%
J 2
(-720 3625);
DISPLAY 0.617021 (-720 3625);
PAINT SKYBLUE (-720 3625);
FORCEPROP 1 LAST VALUE 240
J 2
(-720 3675);
DISPLAY 0.617021 (-720 3675);
PAINT SKYBLUE (-720 3675);
FORCEPROP 1 LAST PART_NUMBER G21796-294
J 2
(-715 3475);
DISPLAY 0.617021 (-715 3475);
PAINT BLUE (-715 3475);
FORCEPROP 1 LAST LOCATION R3R13
J 2
(-720 3725);
DISPLAY 0.617021 (-720 3725);
PAINT AQUA (-720 3725);
FORCEPROP 2 LAST ROOM MEM
J 0
(-700 3750);
PAINT MONO (-700 3750);
DISPLAY INVISIBLE (-700 3750);
FORCEPROP 1 LAST PATH I65
J 2
(-725 3775);
DISPLAY 0.978723 (-725 3775);
PAINT WHITE (-725 3775);
DISPLAY INVISIBLE (-725 3775);
FORCEPROP 2 LAST CDS_LOCATION R3R13
J 2
(-720 3725);
DISPLAY 0.617021 (-720 3725);
PAINT AQUA (-720 3725);
DISPLAY INVISIBLE (-720 3725);
FORCEPROP 2 LAST $SEC 1
J 0
(-725 3825);
DISPLAY 0.936170 (-725 3825);
PAINT MONO (-725 3825);
DISPLAY INVISIBLE (-725 3825);
FORCEPROP 2 LAST CDS_SEC 1
J 0
(-725 3825);
DISPLAY 1.404255 (-725 3825);
PAINT ORANGE (-725 3825);
DISPLAY INVISIBLE (-725 3825);
FORCEPROP 2 LAST BOM_COST SM_CONTROLLER
J 2
(-1250 3700);
DISPLAY 1.617021 (-1250 3700);
PAINT PEACH (-1250 3700);
DISPLAY INVISIBLE (-1250 3700);
FORCEPROP 2 LAST CD_SEC 1
J 0
(-725 3850);
DISPLAY 1.617021 (-725 3850);
PAINT MONO (-725 3850);
DISPLAY INVISIBLE (-725 3850);
FORCEPROP 2 LAST SIGNAL_MODEL DEFAULT_RESISTOR_750OHM_2_1
J 0
(-725 3850);
DISPLAY 1.617021 (-725 3850);
PAINT MONO (-725 3850);
DISPLAY INVISIBLE (-725 3850);
FORCEPROP 2 LAST CDS_LIB mstr_discrete
J 0
(-675 3600);
PAINT MONO (-675 3600);
DISPLAY INVISIBLE (-675 3600);
FORCEADD PVCCIO_CPU0..1
(-925 3925);
FORCEPROP 3 LASTPIN (-925 3875) SIG_NAME PVCCIO_CPU0\g
J 0
(-915 3885);
DISPLAY 0.659574 (-915 3885);
PAINT MONO (-915 3885);
DISPLAY INVISIBLE (-915 3885);
FORCEPROP 1 LAST PATH I66
J 0
(-875 3950);
DISPLAY 0.872340 (-875 3950);
PAINT AQUA (-875 3950);
DISPLAY INVISIBLE (-875 3950);
FORCEPROP 2 LAST CDS_LIB mstr_symbols
J 0
(-925 3925);
PAINT ORANGE (-925 3925);
DISPLAY INVISIBLE (-925 3925);
FORCEPROP 1 LAST VOLTAGE 1.1V
J 0
(-970 3882);
DISPLAY 0.340426 (-970 3882);
PAINT SKYBLUE (-970 3882);
DISPLAY INVISIBLE (-970 3882);
FORCEPROP 1 LAST BODY_TYPE PLUMBING
J 0
(-970 3882);
DISPLAY 0.340426 (-970 3882);
PAINT GREEN (-970 3882);
DISPLAY INVISIBLE (-970 3882);
FORCEPROP 1 LAST HDL_POWER PVCCIO_CPU0
J 1
(-925 3975);
DISPLAY 0.872340 (-925 3975);
PAINT GREEN (-925 3975);
DISPLAY INVISIBLE (-925 3975);
FORCEADD RES..2
R 2
(-1050 3600);
FORCEPROP 1 LASTPIN (-1050 3700) $PN 1
J 2
(-1055 3662);
DISPLAY 0.617021 (-1055 3662);
PAINT MONO (-1055 3662);
FORCEPROP 1 LASTPIN (-1050 3500) $PN 2
J 2
(-1055 3510);
DISPLAY 0.617021 (-1055 3510);
PAINT MONO (-1055 3510);
FORCEPROP 1 LAST LOCATION R3P60
J 2
(-1095 3725);
DISPLAY 0.617021 (-1095 3725);
PAINT AQUA (-1095 3725);
FORCEPROP 1 LAST VALUE 240
J 2
(-1095 3675);
DISPLAY 0.617021 (-1095 3675);
PAINT SKYBLUE (-1095 3675);
FORCEPROP 1 LAST TOLERANCE 1.0%
J 2
(-1095 3625);
DISPLAY 0.617021 (-1095 3625);
PAINT SKYBLUE (-1095 3625);
FORCEPROP 1 LAST MATERIAL CHIP
J 2
(-1090 3525);
DISPLAY 0.617021 (-1090 3525);
PAINT SKYBLUE (-1090 3525);
FORCEPROP 1 LAST PACK_TYPE 0402
J 2
(-1090 3425);
DISPLAY 0.617021 (-1090 3425);
PAINT SKYBLUE (-1090 3425);
FORCEPROP 1 LAST WATTAGE 1/16W
J 2
(-1090 3575);
DISPLAY 0.617021 (-1090 3575);
PAINT SKYBLUE (-1090 3575);
FORCEPROP 1 LAST PART_NUMBER G21796-294
J 2
(-1090 3475);
DISPLAY 0.617021 (-1090 3475);
PAINT BLUE (-1090 3475);
FORCEPROP 2 LAST ROOM MEM
J 0
(-1075 3750);
PAINT MONO (-1075 3750);
DISPLAY INVISIBLE (-1075 3750);
FORCEPROP 1 LAST PATH I67
J 2
(-1100 3775);
DISPLAY 0.978723 (-1100 3775);
PAINT WHITE (-1100 3775);
DISPLAY INVISIBLE (-1100 3775);
FORCEPROP 2 LAST $SEC 1
J 0
(-1100 3825);
DISPLAY 0.936170 (-1100 3825);
PAINT MONO (-1100 3825);
DISPLAY INVISIBLE (-1100 3825);
FORCEPROP 2 LAST CDS_SEC 1
J 0
(-1100 3825);
DISPLAY 1.404255 (-1100 3825);
PAINT ORANGE (-1100 3825);
DISPLAY INVISIBLE (-1100 3825);
FORCEPROP 2 LAST BOM_COST SM_CONTROLLER
J 2
(-1625 3700);
DISPLAY 1.617021 (-1625 3700);
PAINT PEACH (-1625 3700);
DISPLAY INVISIBLE (-1625 3700);
FORCEPROP 2 LAST CDS_LIB mstr_discrete
J 0
(-1050 3600);
PAINT MONO (-1050 3600);
DISPLAY INVISIBLE (-1050 3600);
FORCEPROP 2 LAST SIGNAL_MODEL DEFAULT_RESISTOR_750OHM_2_1
J 0
(-1100 3850);
DISPLAY 1.617021 (-1100 3850);
PAINT MONO (-1100 3850);
DISPLAY INVISIBLE (-1100 3850);
FORCEPROP 2 LAST CD_SEC 1
J 0
(-1100 3850);
DISPLAY 1.617021 (-1100 3850);
PAINT MONO (-1100 3850);
DISPLAY INVISIBLE (-1100 3850);
FORCEADD PVCCIO_CPU1..1
(-525 2675);
FORCEPROP 3 LASTPIN (-525 2625) SIG_NAME PVCCIO_CPU1\g
J 0
(-515 2635);
DISPLAY 0.659574 (-515 2635);
PAINT MONO (-515 2635);
DISPLAY INVISIBLE (-515 2635);
FORCEPROP 1 LAST PATH I69
J 0
(-475 2700);
DISPLAY 0.872340 (-475 2700);
PAINT AQUA (-475 2700);
DISPLAY INVISIBLE (-475 2700);
FORCEPROP 2 LAST CDS_LIB mstr_symbols
J 0
(-525 2675);
PAINT ORANGE (-525 2675);
DISPLAY INVISIBLE (-525 2675);
FORCEPROP 1 LAST VOLTAGE 1.1V
J 0
(-570 2632);
DISPLAY 0.340426 (-570 2632);
PAINT SKYBLUE (-570 2632);
DISPLAY INVISIBLE (-570 2632);
FORCEPROP 1 LAST BODY_TYPE PLUMBING
J 0
(-570 2632);
DISPLAY 0.340426 (-570 2632);
PAINT GREEN (-570 2632);
DISPLAY INVISIBLE (-570 2632);
FORCEPROP 1 LAST HDL_POWER PVCCIO_CPU1
J 1
(-525 2725);
DISPLAY 0.872340 (-525 2725);
PAINT GREEN (-525 2725);
DISPLAY INVISIBLE (-525 2725);
FORCEADD CAP_A..1
(1475 4900);
FORCEPROP 1 LAST PACK_TYPE 0402V
J 0
(1525 4700);
DISPLAY 0.617021 (1525 4700);
PAINT SKYBLUE (1525 4700);
FORCEPROP 1 LAST PART_NUMBER A36096-030
J 0
(1525 4750);
DISPLAY 0.617021 (1525 4750);
PAINT BLUE (1525 4750);
FORCEPROP 1 LAST MATERIAL X7R
J 0
(1525 4800);
DISPLAY 0.617021 (1525 4800);
PAINT SKYBLUE (1525 4800);
FORCEPROP 1 LAST TOLERANCE 10%
J 0
(1525 4850);
DISPLAY 0.617021 (1525 4850);
PAINT SKYBLUE (1525 4850);
FORCEPROP 1 LASTPIN (1475 4800) $PN 2
J 0
(1485 4780);
DISPLAY 0.617021 (1485 4780);
PAINT MONO (1485 4780);
FORCEPROP 1 LASTPIN (1475 5000) $PN 1
J 0
(1485 4980);
DISPLAY 0.617021 (1485 4980);
PAINT MONO (1485 4980);
FORCEPROP 1 LAST VOLTAGE 16V
J 0
(1525 4900);
DISPLAY 0.617021 (1525 4900);
PAINT SKYBLUE (1525 4900);
FORCEPROP 1 LAST VALUE 0.1UF
J 0
(1525 4950);
DISPLAY 0.617021 (1525 4950);
PAINT SKYBLUE (1525 4950);
FORCEPROP 1 LAST LOCATION C6F3
J 0
(1525 5000);
DISPLAY 0.617021 (1525 5000);
PAINT AQUA (1525 5000);
FORCEPROP 2 LAST $SEC 1
J 0
(1525 5100);
DISPLAY 0.936170 (1525 5100);
PAINT MONO (1525 5100);
DISPLAY INVISIBLE (1525 5100);
FORCEPROP 2 LAST CDS_SEC 1
J 0
(1525 5100);
DISPLAY 1.404255 (1525 5100);
PAINT ORANGE (1525 5100);
DISPLAY INVISIBLE (1525 5100);
FORCEPROP 2 LAST CDS_LIB dev_discrete
J 0
(1475 4900);
PAINT ORANGE (1475 4900);
DISPLAY INVISIBLE (1475 4900);
FORCEPROP 2 LAST SIGNAL_MODEL DEFAULT_CAPACITOR_100000pF_2_1
J 0
(1525 5125);
DISPLAY 1.617021 (1525 5125);
PAINT MONO (1525 5125);
DISPLAY INVISIBLE (1525 5125);
FORCEPROP 2 LAST CD_SEC 1
J 0
(1525 5125);
DISPLAY 1.617021 (1525 5125);
PAINT MONO (1525 5125);
DISPLAY INVISIBLE (1525 5125);
FORCEPROP 2 LAST BOM_COST SM_CONTROLLER
J 0
(1525 5050);
DISPLAY 2.170213 (1525 5050);
PAINT ORANGE (1525 5050);
DISPLAY INVISIBLE (1525 5050);
FORCEPROP 2 LAST CDS_LOCATION C6F3
J 0
(1525 5000);
DISPLAY 0.617021 (1525 5000);
PAINT AQUA (1525 5000);
DISPLAY INVISIBLE (1525 5000);
FORCEPROP 2 LAST ROOM MEM
J 0
(1525 5025);
PAINT MONO (1525 5025);
DISPLAY INVISIBLE (1525 5025);
FORCEPROP 1 LAST PATH I7
J 0
(1525 5050);
DISPLAY 0.978723 (1525 5050);
PAINT WHITE (1525 5050);
DISPLAY INVISIBLE (1525 5050);
FORCEADD RES..2
R 2
(-700 2450);
FORCEPROP 1 LASTPIN (-700 2550) $PN 1
J 2
(-705 2512);
DISPLAY 0.617021 (-705 2512);
PAINT MONO (-705 2512);
FORCEPROP 1 LASTPIN (-700 2350) $PN 2
J 2
(-705 2360);
DISPLAY 0.617021 (-705 2360);
PAINT MONO (-705 2360);
FORCEPROP 1 LAST WATTAGE 1/16W
J 2
(-740 2425);
DISPLAY 0.617021 (-740 2425);
PAINT SKYBLUE (-740 2425);
FORCEPROP 1 LAST MATERIAL CHIP
J 2
(-740 2375);
DISPLAY 0.617021 (-740 2375);
PAINT SKYBLUE (-740 2375);
FORCEPROP 1 LAST PACK_TYPE 0402
J 2
(-740 2275);
DISPLAY 0.617021 (-740 2275);
PAINT SKYBLUE (-740 2275);
FORCEPROP 1 LAST TOLERANCE 1.0%
J 2
(-745 2475);
DISPLAY 0.617021 (-745 2475);
PAINT SKYBLUE (-745 2475);
FORCEPROP 1 LAST VALUE 240
J 2
(-745 2525);
DISPLAY 0.617021 (-745 2525);
PAINT SKYBLUE (-745 2525);
FORCEPROP 1 LAST LOCATION R6T1
J 2
(-745 2575);
DISPLAY 0.617021 (-745 2575);
PAINT AQUA (-745 2575);
FORCEPROP 1 LAST PART_NUMBER G21796-294
J 2
(-740 2325);
DISPLAY 0.617021 (-740 2325);
PAINT BLUE (-740 2325);
FORCEPROP 2 LAST ROOM MEM
J 0
(-725 2600);
PAINT MONO (-725 2600);
DISPLAY INVISIBLE (-725 2600);
FORCEPROP 1 LAST PATH I70
J 2
(-750 2625);
DISPLAY 0.978723 (-750 2625);
PAINT WHITE (-750 2625);
DISPLAY INVISIBLE (-750 2625);
FORCEPROP 2 LAST CDS_LOCATION R6T1
J 2
(-745 2575);
DISPLAY 0.617021 (-745 2575);
PAINT AQUA (-745 2575);
DISPLAY INVISIBLE (-745 2575);
FORCEPROP 2 LAST $SEC 1
J 0
(-750 2675);
DISPLAY 0.936170 (-750 2675);
PAINT MONO (-750 2675);
DISPLAY INVISIBLE (-750 2675);
FORCEPROP 2 LAST CDS_SEC 1
J 0
(-750 2675);
DISPLAY 1.404255 (-750 2675);
PAINT ORANGE (-750 2675);
DISPLAY INVISIBLE (-750 2675);
FORCEPROP 2 LAST BOM_COST SM_CONTROLLER
J 2
(-1275 2550);
DISPLAY 1.617021 (-1275 2550);
PAINT PEACH (-1275 2550);
DISPLAY INVISIBLE (-1275 2550);
FORCEPROP 2 LAST SIGNAL_MODEL DEFAULT_RESISTOR_750OHM_2_1
J 0
(-750 2700);
DISPLAY 1.617021 (-750 2700);
PAINT MONO (-750 2700);
DISPLAY INVISIBLE (-750 2700);
FORCEPROP 2 LAST CD_SEC 1
J 0
(-750 2700);
DISPLAY 1.617021 (-750 2700);
PAINT MONO (-750 2700);
DISPLAY INVISIBLE (-750 2700);
FORCEPROP 2 LAST CDS_LIB mstr_discrete
J 0
(-700 2450);
PAINT MONO (-700 2450);
DISPLAY INVISIBLE (-700 2450);
FORCEADD PVCCIO_CPU1..1
(-950 2775);
FORCEPROP 3 LASTPIN (-950 2725) SIG_NAME PVCCIO_CPU1\g
J 0
(-940 2735);
DISPLAY 0.659574 (-940 2735);
PAINT MONO (-940 2735);
DISPLAY INVISIBLE (-940 2735);
FORCEPROP 1 LAST PATH I71
J 0
(-900 2800);
DISPLAY 0.872340 (-900 2800);
PAINT AQUA (-900 2800);
DISPLAY INVISIBLE (-900 2800);
FORCEPROP 2 LAST CDS_LIB mstr_symbols
J 0
(-950 2775);
PAINT ORANGE (-950 2775);
DISPLAY INVISIBLE (-950 2775);
FORCEPROP 1 LAST VOLTAGE 1.1V
J 0
(-995 2732);
DISPLAY 0.340426 (-995 2732);
PAINT SKYBLUE (-995 2732);
DISPLAY INVISIBLE (-995 2732);
FORCEPROP 1 LAST BODY_TYPE PLUMBING
J 0
(-995 2732);
DISPLAY 0.340426 (-995 2732);
PAINT GREEN (-995 2732);
DISPLAY INVISIBLE (-995 2732);
FORCEPROP 1 LAST HDL_POWER PVCCIO_CPU1
J 1
(-950 2825);
DISPLAY 0.872340 (-950 2825);
PAINT GREEN (-950 2825);
DISPLAY INVISIBLE (-950 2825);
FORCEADD RES..2
R 2
(-1075 2450);
FORCEPROP 1 LAST PART_NUMBER G21796-294
J 2
(-1115 2325);
DISPLAY 0.617021 (-1115 2325);
PAINT BLUE (-1115 2325);
FORCEPROP 1 LASTPIN (-1075 2550) $PN 1
J 2
(-1080 2512);
DISPLAY 0.617021 (-1080 2512);
PAINT MONO (-1080 2512);
FORCEPROP 1 LASTPIN (-1075 2350) $PN 2
J 2
(-1080 2360);
DISPLAY 0.617021 (-1080 2360);
PAINT MONO (-1080 2360);
FORCEPROP 1 LAST WATTAGE 1/16W
J 2
(-1115 2425);
DISPLAY 0.617021 (-1115 2425);
PAINT SKYBLUE (-1115 2425);
FORCEPROP 1 LAST MATERIAL CHIP
J 2
(-1115 2375);
DISPLAY 0.617021 (-1115 2375);
PAINT SKYBLUE (-1115 2375);
FORCEPROP 1 LAST PACK_TYPE 0402
J 2
(-1115 2275);
DISPLAY 0.617021 (-1115 2275);
PAINT SKYBLUE (-1115 2275);
FORCEPROP 1 LAST TOLERANCE 1.0%
J 2
(-1120 2475);
DISPLAY 0.617021 (-1120 2475);
PAINT SKYBLUE (-1120 2475);
FORCEPROP 1 LAST VALUE 240
J 2
(-1120 2525);
DISPLAY 0.617021 (-1120 2525);
PAINT SKYBLUE (-1120 2525);
FORCEPROP 1 LAST LOCATION R6T2
J 2
(-1120 2575);
DISPLAY 0.617021 (-1120 2575);
PAINT AQUA (-1120 2575);
FORCEPROP 2 LAST ROOM MEM
J 0
(-1100 2600);
PAINT MONO (-1100 2600);
DISPLAY INVISIBLE (-1100 2600);
FORCEPROP 1 LAST PATH I72
J 2
(-1125 2625);
DISPLAY 0.978723 (-1125 2625);
PAINT WHITE (-1125 2625);
DISPLAY INVISIBLE (-1125 2625);
FORCEPROP 2 LAST CDS_LOCATION R6T2
J 2
(-1120 2575);
DISPLAY 0.617021 (-1120 2575);
PAINT AQUA (-1120 2575);
DISPLAY INVISIBLE (-1120 2575);
FORCEPROP 2 LAST $SEC 1
J 0
(-1125 2675);
DISPLAY 0.936170 (-1125 2675);
PAINT MONO (-1125 2675);
DISPLAY INVISIBLE (-1125 2675);
FORCEPROP 2 LAST CDS_SEC 1
J 0
(-1125 2675);
DISPLAY 1.404255 (-1125 2675);
PAINT ORANGE (-1125 2675);
DISPLAY INVISIBLE (-1125 2675);
FORCEPROP 2 LAST BOM_COST SM_CONTROLLER
J 2
(-1650 2550);
DISPLAY 1.617021 (-1650 2550);
PAINT PEACH (-1650 2550);
DISPLAY INVISIBLE (-1650 2550);
FORCEPROP 2 LAST CD_SEC 1
J 0
(-1125 2700);
DISPLAY 1.617021 (-1125 2700);
PAINT MONO (-1125 2700);
DISPLAY INVISIBLE (-1125 2700);
FORCEPROP 2 LAST SIGNAL_MODEL DEFAULT_RESISTOR_750OHM_2_1
J 0
(-1125 2700);
DISPLAY 1.617021 (-1125 2700);
PAINT MONO (-1125 2700);
DISPLAY INVISIBLE (-1125 2700);
FORCEPROP 2 LAST CDS_LIB mstr_discrete
J 0
(-1075 2450);
PAINT MONO (-1075 2450);
DISPLAY INVISIBLE (-1075 2450);
FORCEADD PVPP_KLM..1
(575 1225);
FORCEPROP 3 LASTPIN (575 1175) SIG_NAME PVPP_KLM\g
J 0
(585 1185);
DISPLAY 0.659574 (585 1185);
PAINT MONO (585 1185);
DISPLAY INVISIBLE (585 1185);
FORCEPROP 2 LAST ROOM SMB
J 0
(575 1300);
PAINT MONO (575 1300);
DISPLAY INVISIBLE (575 1300);
FORCEPROP 1 LAST PATH I74
J 0
(625 1250);
DISPLAY 0.872340 (625 1250);
PAINT AQUA (625 1250);
DISPLAY INVISIBLE (625 1250);
FORCEPROP 2 LAST CDS_LIB mstr_symbols
J 0
(575 1225);
PAINT ORANGE (575 1225);
DISPLAY INVISIBLE (575 1225);
FORCEPROP 2 LAST BOM_COST SM_CONTROLLER
J 0
(575 1325);
DISPLAY 1.617021 (575 1325);
PAINT ORANGE (575 1325);
DISPLAY INVISIBLE (575 1325);
FORCEPROP 1 LAST VOLTAGE 2.5V
J 0
(530 1182);
DISPLAY 0.340426 (530 1182);
PAINT SKYBLUE (530 1182);
DISPLAY INVISIBLE (530 1182);
FORCEPROP 1 LAST BODY_TYPE PLUMBING
J 0
(530 1182);
DISPLAY 0.340426 (530 1182);
PAINT GREEN (530 1182);
DISPLAY INVISIBLE (530 1182);
FORCEPROP 1 LAST HDL_POWER PVPP_KLM
J 1
(575 1275);
DISPLAY 0.872340 (575 1275);
PAINT GREEN (575 1275);
DISPLAY INVISIBLE (575 1275);
FORCEADD PCA9617..1
(150 900);
FORCEPROP 2 LASTPIN (-250 800) $PN 5
J 2
(-260 810);
DISPLAY 0.617021 (-260 810);
PAINT MONO (-260 810);
FORCEPROP 2 LASTPIN (-250 950) $PN 2
J 2
(-260 960);
DISPLAY 0.617021 (-260 960);
PAINT MONO (-260 960);
FORCEPROP 2 LASTPIN (550 950) $PN 7
J 0
(560 960);
DISPLAY 0.617021 (560 960);
PAINT MONO (560 960);
FORCEPROP 2 LASTPIN (-250 900) $PN 3
J 2
(-260 910);
DISPLAY 0.617021 (-260 910);
PAINT MONO (-260 910);
FORCEPROP 2 LASTPIN (550 900) $PN 6
J 0
(560 910);
DISPLAY 0.617021 (560 910);
PAINT MONO (560 910);
FORCEPROP 2 LASTPIN (550 1050) $PN 8
J 0
(560 1060);
DISPLAY 0.617021 (560 1060);
PAINT MONO (560 1060);
FORCEPROP 1 LAST MATERIAL IC
J 0
(-200 1175);
DISPLAY 0.617021 (-200 1175);
PAINT SKYBLUE (-200 1175);
FORCEPROP 1 LAST PART_NUMBER G81764-001
J 0
(-200 700);
DISPLAY 0.617021 (-200 700);
PAINT BLUE (-200 700);
FORCEPROP 1 LAST LOCATION U3B1
J 0
(-200 1225);
DISPLAY 0.617021 (-200 1225);
PAINT AQUA (-200 1225);
FORCEPROP 1 LAST POWER_GROUP GND=GND
J 0
(-200 650);
DISPLAY 0.617021 (-200 650);
PAINT ORANGE (-200 650);
FORCEPROP 2 LASTPIN (-250 1050) $PN 1
J 2
(-260 1060);
DISPLAY 0.617021 (-260 1060);
PAINT MONO (-260 1060);
FORCEPROP 2 LAST ROOM MEM
J 0
(-200 1275);
PAINT MONO (-200 1275);
DISPLAY INVISIBLE (-200 1275);
FORCEPROP 1 LAST PATH I75
J 0
(275 1175);
PAINT GREEN (275 1175);
DISPLAY INVISIBLE (275 1175);
FORCEPROP 2 LAST CDS_LOCATION U3B1
J 0
(-200 1225);
DISPLAY 0.617021 (-200 1225);
PAINT AQUA (-200 1225);
DISPLAY INVISIBLE (-200 1225);
FORCEPROP 2 LAST $SEC 1
J 0
(-200 1275);
DISPLAY 0.936170 (-200 1275);
PAINT MONO (-200 1275);
DISPLAY INVISIBLE (-200 1275);
FORCEPROP 2 LAST CDS_SEC 1
J 0
(-200 1275);
DISPLAY 1.404255 (-200 1275);
PAINT ORANGE (-200 1275);
DISPLAY INVISIBLE (-200 1275);
FORCEPROP 2 LAST BOM_COST SM_CONTROLLER
J 0
(-200 1275);
PAINT MONO (-200 1275);
DISPLAY INVISIBLE (-200 1275);
FORCEPROP 2 LAST CDS_LIB mstr_digital
J 0
(150 900);
PAINT MONO (150 900);
DISPLAY INVISIBLE (150 900);
FORCEPROP 1 LAST PACK_TYPE SSOP
J 0
(-200 1275);
PAINT SKYBLUE (-200 1275);
DISPLAY INVISIBLE (-200 1275);
FORCEADD PVCCIO_CPU1..1
(-550 1475);
FORCEPROP 3 LASTPIN (-550 1425) SIG_NAME PVCCIO_CPU1\g
J 0
(-540 1435);
DISPLAY 0.659574 (-540 1435);
PAINT MONO (-540 1435);
DISPLAY INVISIBLE (-540 1435);
FORCEPROP 1 LAST PATH I76
J 0
(-500 1500);
DISPLAY 0.872340 (-500 1500);
PAINT AQUA (-500 1500);
DISPLAY INVISIBLE (-500 1500);
FORCEPROP 2 LAST CDS_LIB mstr_symbols
J 0
(-550 1475);
PAINT ORANGE (-550 1475);
DISPLAY INVISIBLE (-550 1475);
FORCEPROP 1 LAST VOLTAGE 1.1V
J 0
(-595 1432);
DISPLAY 0.340426 (-595 1432);
PAINT SKYBLUE (-595 1432);
DISPLAY INVISIBLE (-595 1432);
FORCEPROP 1 LAST BODY_TYPE PLUMBING
J 0
(-595 1432);
DISPLAY 0.340426 (-595 1432);
PAINT GREEN (-595 1432);
DISPLAY INVISIBLE (-595 1432);
FORCEPROP 1 LAST HDL_POWER PVCCIO_CPU1
J 1
(-550 1525);
DISPLAY 0.872340 (-550 1525);
PAINT GREEN (-550 1525);
DISPLAY INVISIBLE (-550 1525);
FORCEADD RES..2
R 2
(-725 1250);
FORCEPROP 1 LASTPIN (-725 1350) $PN 1
J 2
(-730 1312);
DISPLAY 0.617021 (-730 1312);
PAINT MONO (-730 1312);
FORCEPROP 1 LASTPIN (-725 1150) $PN 2
J 2
(-730 1160);
DISPLAY 0.617021 (-730 1160);
PAINT MONO (-730 1160);
FORCEPROP 1 LAST WATTAGE 1/16W
J 2
(-765 1225);
DISPLAY 0.617021 (-765 1225);
PAINT SKYBLUE (-765 1225);
FORCEPROP 1 LAST MATERIAL CHIP
J 2
(-765 1175);
DISPLAY 0.617021 (-765 1175);
PAINT SKYBLUE (-765 1175);
FORCEPROP 1 LAST PACK_TYPE 0402
J 2
(-765 1075);
DISPLAY 0.617021 (-765 1075);
PAINT SKYBLUE (-765 1075);
FORCEPROP 1 LAST TOLERANCE 1.0%
J 2
(-770 1275);
DISPLAY 0.617021 (-770 1275);
PAINT SKYBLUE (-770 1275);
FORCEPROP 1 LAST VALUE 240
J 2
(-770 1325);
DISPLAY 0.617021 (-770 1325);
PAINT SKYBLUE (-770 1325);
FORCEPROP 1 LAST PART_NUMBER G21796-294
J 2
(-765 1125);
DISPLAY 0.617021 (-765 1125);
PAINT BLUE (-765 1125);
FORCEPROP 1 LAST LOCATION R7M7
J 2
(-770 1375);
DISPLAY 0.617021 (-770 1375);
PAINT AQUA (-770 1375);
FORCEPROP 2 LAST ROOM MEM
J 0
(-750 1400);
PAINT MONO (-750 1400);
DISPLAY INVISIBLE (-750 1400);
FORCEPROP 1 LAST PATH I77
J 2
(-775 1425);
DISPLAY 0.978723 (-775 1425);
PAINT WHITE (-775 1425);
DISPLAY INVISIBLE (-775 1425);
FORCEPROP 2 LAST CDS_LOCATION R7M7
J 2
(-770 1375);
DISPLAY 0.617021 (-770 1375);
PAINT AQUA (-770 1375);
DISPLAY INVISIBLE (-770 1375);
FORCEPROP 2 LAST $SEC 1
J 0
(-775 1475);
DISPLAY 0.936170 (-775 1475);
PAINT MONO (-775 1475);
DISPLAY INVISIBLE (-775 1475);
FORCEPROP 2 LAST CDS_SEC 1
J 0
(-775 1475);
DISPLAY 1.404255 (-775 1475);
PAINT ORANGE (-775 1475);
DISPLAY INVISIBLE (-775 1475);
FORCEPROP 2 LAST BOM_COST SM_CONTROLLER
J 2
(-1300 1350);
DISPLAY 1.617021 (-1300 1350);
PAINT PEACH (-1300 1350);
DISPLAY INVISIBLE (-1300 1350);
FORCEPROP 2 LAST SIGNAL_MODEL DEFAULT_RESISTOR_750OHM_2_1
J 0
(-775 1500);
DISPLAY 1.617021 (-775 1500);
PAINT MONO (-775 1500);
DISPLAY INVISIBLE (-775 1500);
FORCEPROP 2 LAST CD_SEC 1
J 0
(-775 1500);
DISPLAY 1.617021 (-775 1500);
PAINT MONO (-775 1500);
DISPLAY INVISIBLE (-775 1500);
FORCEPROP 2 LAST CDS_LIB mstr_discrete
J 0
(-725 1250);
PAINT MONO (-725 1250);
DISPLAY INVISIBLE (-725 1250);
FORCEADD PVCCIO_CPU1..1
(-975 1575);
FORCEPROP 3 LASTPIN (-975 1525) SIG_NAME PVCCIO_CPU1\g
J 0
(-965 1535);
DISPLAY 0.659574 (-965 1535);
PAINT MONO (-965 1535);
DISPLAY INVISIBLE (-965 1535);
FORCEPROP 1 LAST PATH I78
J 0
(-925 1600);
DISPLAY 0.872340 (-925 1600);
PAINT AQUA (-925 1600);
DISPLAY INVISIBLE (-925 1600);
FORCEPROP 2 LAST CDS_LIB mstr_symbols
J 0
(-975 1575);
PAINT ORANGE (-975 1575);
DISPLAY INVISIBLE (-975 1575);
FORCEPROP 1 LAST VOLTAGE 1.1V
J 0
(-1020 1532);
DISPLAY 0.340426 (-1020 1532);
PAINT SKYBLUE (-1020 1532);
DISPLAY INVISIBLE (-1020 1532);
FORCEPROP 1 LAST BODY_TYPE PLUMBING
J 0
(-1020 1532);
DISPLAY 0.340426 (-1020 1532);
PAINT GREEN (-1020 1532);
DISPLAY INVISIBLE (-1020 1532);
FORCEPROP 1 LAST HDL_POWER PVCCIO_CPU1
J 1
(-975 1625);
DISPLAY 0.872340 (-975 1625);
PAINT GREEN (-975 1625);
DISPLAY INVISIBLE (-975 1625);
FORCEADD RES..2
R 2
(-1100 1250);
FORCEPROP 1 LASTPIN (-1100 1350) $PN 1
J 2
(-1105 1312);
DISPLAY 0.617021 (-1105 1312);
PAINT MONO (-1105 1312);
FORCEPROP 1 LASTPIN (-1100 1150) $PN 2
J 2
(-1105 1160);
DISPLAY 0.617021 (-1105 1160);
PAINT MONO (-1105 1160);
FORCEPROP 1 LAST WATTAGE 1/16W
J 2
(-1140 1225);
DISPLAY 0.617021 (-1140 1225);
PAINT SKYBLUE (-1140 1225);
FORCEPROP 1 LAST MATERIAL CHIP
J 2
(-1140 1175);
DISPLAY 0.617021 (-1140 1175);
PAINT SKYBLUE (-1140 1175);
FORCEPROP 1 LAST TOLERANCE 1.0%
J 2
(-1145 1275);
DISPLAY 0.617021 (-1145 1275);
PAINT SKYBLUE (-1145 1275);
FORCEPROP 1 LAST VALUE 240
J 2
(-1145 1325);
DISPLAY 0.617021 (-1145 1325);
PAINT SKYBLUE (-1145 1325);
FORCEPROP 1 LAST PART_NUMBER G21796-294
J 2
(-1140 1125);
DISPLAY 0.617021 (-1140 1125);
PAINT BLUE (-1140 1125);
FORCEPROP 1 LAST LOCATION R7M2
J 2
(-1145 1375);
DISPLAY 0.617021 (-1145 1375);
PAINT AQUA (-1145 1375);
FORCEPROP 1 LAST PACK_TYPE 0402
J 2
(-1140 1075);
DISPLAY 0.617021 (-1140 1075);
PAINT SKYBLUE (-1140 1075);
FORCEPROP 2 LAST ROOM MEM
J 0
(-1125 1400);
PAINT MONO (-1125 1400);
DISPLAY INVISIBLE (-1125 1400);
FORCEPROP 1 LAST PATH I79
J 2
(-1150 1425);
DISPLAY 0.978723 (-1150 1425);
PAINT WHITE (-1150 1425);
DISPLAY INVISIBLE (-1150 1425);
FORCEPROP 2 LAST CDS_LOCATION R7M2
J 2
(-1145 1375);
DISPLAY 0.617021 (-1145 1375);
PAINT AQUA (-1145 1375);
DISPLAY INVISIBLE (-1145 1375);
FORCEPROP 2 LAST $SEC 1
J 0
(-1150 1475);
DISPLAY 0.936170 (-1150 1475);
PAINT MONO (-1150 1475);
DISPLAY INVISIBLE (-1150 1475);
FORCEPROP 2 LAST CDS_SEC 1
J 0
(-1150 1475);
DISPLAY 1.404255 (-1150 1475);
PAINT ORANGE (-1150 1475);
DISPLAY INVISIBLE (-1150 1475);
FORCEPROP 2 LAST BOM_COST SM_CONTROLLER
J 2
(-1675 1350);
DISPLAY 1.617021 (-1675 1350);
PAINT PEACH (-1675 1350);
DISPLAY INVISIBLE (-1675 1350);
FORCEPROP 2 LAST SIGNAL_MODEL DEFAULT_RESISTOR_750OHM_2_1
J 0
(-1150 1500);
DISPLAY 1.617021 (-1150 1500);
PAINT MONO (-1150 1500);
DISPLAY INVISIBLE (-1150 1500);
FORCEPROP 2 LAST CD_SEC 1
J 0
(-1150 1500);
DISPLAY 1.617021 (-1150 1500);
PAINT MONO (-1150 1500);
DISPLAY INVISIBLE (-1150 1500);
FORCEPROP 2 LAST CDS_LIB mstr_discrete
J 0
(-1100 1250);
PAINT MONO (-1100 1250);
DISPLAY INVISIBLE (-1100 1250);
FORCEADD GND..1
(1475 4650);
FORCEPROP 3 LASTPIN (1475 4700) SIG_NAME GND\g
J 0
(1485 4710);
DISPLAY 0.659574 (1485 4710);
PAINT MONO (1485 4710);
DISPLAY INVISIBLE (1485 4710);
FORCEPROP 2 LAST ROOM SMB
J 0
(1375 4725);
PAINT MONO (1375 4725);
DISPLAY INVISIBLE (1375 4725);
FORCEPROP 1 LAST PATH I8
J 0
(1550 4650);
DISPLAY 0.872340 (1550 4650);
PAINT AQUA (1550 4650);
DISPLAY INVISIBLE (1550 4650);
FORCEPROP 1 LAST SIZE 1B
J 0
(1550 4600);
DISPLAY 2.361702 (1550 4600);
PAINT GREEN (1550 4600);
DISPLAY INVISIBLE (1550 4600);
FORCEPROP 2 LAST CDS_LIB mstr_symbols
J 0
(1475 4650);
PAINT MONO (1475 4650);
DISPLAY INVISIBLE (1475 4650);
FORCEPROP 2 LAST BOM_COST SM_CONTROLLER
J 0
(1075 4725);
DISPLAY 1.617021 (1075 4725);
PAINT ORANGE (1075 4725);
DISPLAY INVISIBLE (1075 4725);
FORCEPROP 1 LAST VOLTAGE 0
J 0
(1475 4650);
PAINT SKYBLUE (1475 4650);
DISPLAY INVISIBLE (1475 4650);
FORCEPROP 1 LAST BODY_TYPE PLUMBING
J 0
(1430 4607);
DISPLAY 0.340426 (1430 4607);
PAINT GREEN (1430 4607);
DISPLAY INVISIBLE (1430 4607);
FORCEPROP 1 LAST HDL_POWER GND
J 0
(1475 4800);
DISPLAY 2.361702 (1475 4800);
PAINT GREEN (1475 4800);
DISPLAY INVISIBLE (1475 4800);
FORCEADD RES..1
(-1500 4350);
FORCEPROP 1 LASTPIN (-1400 4350) $PN 2
J 0
(-1438 4362);
DISPLAY 0.617021 (-1438 4362);
PAINT MONO (-1438 4362);
FORCEPROP 1 LASTPIN (-1600 4350) $PN 1
J 0
(-1588 4362);
DISPLAY 0.617021 (-1588 4362);
PAINT MONO (-1588 4362);
FORCEPROP 1 LAST PART_NUMBER G21796-066
J 0
(-1850 4425);
DISPLAY 0.617021 (-1850 4425);
PAINT BLUE (-1850 4425);
FORCEPROP 1 LAST WATTAGE 1/16W
J 2
(-1400 4475);
DISPLAY 0.617021 (-1400 4475);
PAINT SKYBLUE (-1400 4475);
FORCEPROP 1 LAST PACK_TYPE 0402
J 0
(-1575 4425);
DISPLAY 0.617021 (-1575 4425);
PAINT SKYBLUE (-1575 4425);
FORCEPROP 1 LAST TOLERANCE 1%
J 0
(-1650 4475);
DISPLAY 0.617021 (-1650 4475);
PAINT SKYBLUE (-1650 4475);
FORCEPROP 1 LAST MATERIAL CHIP
J 0
(-2000 4425);
DISPLAY 0.617021 (-2000 4425);
PAINT SKYBLUE (-2000 4425);
FORCEPROP 1 LAST LOCATION R4T3
J 0
(-2000 4475);
DISPLAY 0.617021 (-2000 4475);
PAINT AQUA (-2000 4475);
FORCEPROP 1 LAST VALUE 10.0
J 2
(-1725 4475);
DISPLAY 0.617021 (-1725 4475);
PAINT SKYBLUE (-1725 4475);
FORCEPROP 2 LAST ROOM MEM
J 0
(-1550 4450);
PAINT MONO (-1550 4450);
DISPLAY INVISIBLE (-1550 4450);
FORCEPROP 1 LAST PATH I83
J 0
(-1550 4500);
DISPLAY 0.978723 (-1550 4500);
PAINT WHITE (-1550 4500);
DISPLAY INVISIBLE (-1550 4500);
FORCEPROP 2 LAST CDS_LOCATION R4T3
J 0
(-1550 4400);
DISPLAY 0.617021 (-1550 4400);
PAINT AQUA (-1550 4400);
DISPLAY INVISIBLE (-1550 4400);
FORCEPROP 2 LAST $SEC 1
J 0
(-1550 4550);
DISPLAY 0.936170 (-1550 4550);
PAINT MONO (-1550 4550);
DISPLAY INVISIBLE (-1550 4550);
FORCEPROP 2 LAST CDS_SEC 1
J 0
(-1550 4550);
DISPLAY 1.404255 (-1550 4550);
PAINT ORANGE (-1550 4550);
DISPLAY INVISIBLE (-1550 4550);
FORCEPROP 2 LAST CDS_LIB mstr_discrete
J 0
(-1500 4350);
PAINT MONO (-1500 4350);
DISPLAY INVISIBLE (-1500 4350);
FORCEPROP 2 LAST BOM_COST SM_CONTROLLER
J 0
(-1550 4450);
PAINT MONO (-1550 4450);
DISPLAY INVISIBLE (-1550 4450);
FORCEADD OFFPAGE..1
(-2325 4350);
FORCEPROP 2 LAST $XR0 21 
J 0
(-2546 4350);
DISPLAY 0.638298 (-2546 4350);
PAINT MONO (-2546 4350);
FORCEPROP 2 LAST PATH I84
J 0
(-2525 4400);
DISPLAY 1.021277 (-2525 4400);
PAINT ORANGE (-2525 4400);
DISPLAY INVISIBLE (-2525 4400);
FORCEPROP 2 LAST ROOM SMB
J 0
(-2575 4400);
PAINT MONO (-2575 4400);
DISPLAY INVISIBLE (-2575 4400);
FORCEPROP 2 LAST CDS_LIB mstr_standard
J 0
(-2325 4350);
PAINT ORANGE (-2325 4350);
DISPLAY INVISIBLE (-2325 4350);
FORCEPROP 2 LAST BOM_COST SM_CONTROLLER
J 0
(-2575 4400);
PAINT MONO (-2575 4400);
DISPLAY INVISIBLE (-2575 4400);
FORCEPROP 1 LAST OFFPAGE TRUE
J 0
(-2000 4225);
PAINT GREEN (-2000 4225);
DISPLAY INVISIBLE (-2000 4225);
FORCEPROP 1 LAST COMMENT_BODY TRUE
J 0
(-2200 4250);
DISPLAY 0.872340 (-2200 4250);
PAINT GREEN (-2200 4250);
DISPLAY INVISIBLE (-2200 4250);
FORCEADD OFFPAGE..6
(-2325 4300);
FORCEPROP 2 LASTPIN (-2275 4300) SIG_NAME SMB_DDR_ABC_SDA_G_R
J 0
(-2210 4310);
DISPLAY 0.617021 (-2210 4310);
PAINT ORANGE (-2210 4310);
FORCEPROP 2 LAST $XR0 21 
J 0
(-2604 4300);
DISPLAY 0.638298 (-2604 4300);
PAINT MONO (-2604 4300);
FORCEPROP 2 LAST PATH I85
J 0
(-2600 4350);
DISPLAY 1.021277 (-2600 4350);
PAINT ORANGE (-2600 4350);
DISPLAY INVISIBLE (-2600 4350);
FORCEPROP 2 LAST CDS_LIB mstr_standard
J 0
(-2325 4300);
PAINT MONO (-2325 4300);
DISPLAY INVISIBLE (-2325 4300);
FORCEPROP 2 LAST BOM_COST SM_CONTROLLER
J 0
(-2550 4350);
DISPLAY 1.617021 (-2550 4350);
PAINT ORANGE (-2550 4350);
DISPLAY INVISIBLE (-2550 4350);
FORCEPROP 1 LAST OFFPAGE TRUE
J 0
(-2000 4175);
PAINT GREEN (-2000 4175);
DISPLAY INVISIBLE (-2000 4175);
FORCEPROP 1 LAST COMMENT_BODY TRUE
J 0
(-2225 4225);
DISPLAY 1.872340 (-2225 4225);
PAINT GREEN (-2225 4225);
DISPLAY INVISIBLE (-2225 4225);
FORCEADD RES..1
(-1575 3300);
FORCEPROP 1 LAST PACK_TYPE 0402
J 0
(-1600 3375);
DISPLAY 0.617021 (-1600 3375);
PAINT SKYBLUE (-1600 3375);
FORCEPROP 1 LAST TOLERANCE 1%
J 0
(-1600 3425);
DISPLAY 0.617021 (-1600 3425);
PAINT SKYBLUE (-1600 3425);
FORCEPROP 1 LASTPIN (-1475 3300) $PN 2
J 0
(-1513 3312);
DISPLAY 0.617021 (-1513 3312);
PAINT MONO (-1513 3312);
FORCEPROP 1 LAST LOCATION R3R7
J 0
(-2025 3425);
DISPLAY 0.617021 (-2025 3425);
PAINT AQUA (-2025 3425);
FORCEPROP 1 LAST MATERIAL CHIP
J 0
(-2025 3375);
DISPLAY 0.617021 (-2025 3375);
PAINT SKYBLUE (-2025 3375);
FORCEPROP 1 LASTPIN (-1675 3300) $PN 1
J 0
(-1663 3312);
DISPLAY 0.617021 (-1663 3312);
PAINT MONO (-1663 3312);
FORCEPROP 1 LAST VALUE 10.0
J 2
(-1775 3425);
DISPLAY 0.617021 (-1775 3425);
PAINT SKYBLUE (-1775 3425);
FORCEPROP 1 LAST PART_NUMBER G21796-066
J 0
(-1875 3375);
DISPLAY 0.617021 (-1875 3375);
PAINT BLUE (-1875 3375);
FORCEPROP 1 LAST WATTAGE 1/16W
J 2
(-1350 3425);
DISPLAY 0.617021 (-1350 3425);
PAINT SKYBLUE (-1350 3425);
FORCEPROP 2 LAST ROOM MEM
J 0
(-1625 3400);
PAINT MONO (-1625 3400);
DISPLAY INVISIBLE (-1625 3400);
FORCEPROP 1 LAST PATH I88
J 0
(-1625 3450);
DISPLAY 0.978723 (-1625 3450);
PAINT WHITE (-1625 3450);
DISPLAY INVISIBLE (-1625 3450);
FORCEPROP 2 LAST CDS_LOCATION R3R7
J 0
(-1625 3350);
DISPLAY 0.617021 (-1625 3350);
PAINT AQUA (-1625 3350);
DISPLAY INVISIBLE (-1625 3350);
FORCEPROP 2 LAST $SEC 1
J 0
(-1625 3500);
DISPLAY 0.936170 (-1625 3500);
PAINT MONO (-1625 3500);
DISPLAY INVISIBLE (-1625 3500);
FORCEPROP 2 LAST CDS_SEC 1
J 0
(-1625 3500);
DISPLAY 1.404255 (-1625 3500);
PAINT ORANGE (-1625 3500);
DISPLAY INVISIBLE (-1625 3500);
FORCEPROP 2 LAST BOM_COST SM_CONTROLLER
J 0
(-1625 3400);
PAINT MONO (-1625 3400);
DISPLAY INVISIBLE (-1625 3400);
FORCEPROP 2 LAST CDS_LIB mstr_discrete
J 0
(-1575 3300);
PAINT MONO (-1575 3300);
DISPLAY INVISIBLE (-1575 3300);
FORCEADD OFFPAGE..1
(-2350 3300);
FORCEPROP 2 LAST $XR0 21 
J 0
(-2571 3300);
DISPLAY 0.638298 (-2571 3300);
PAINT MONO (-2571 3300);
FORCEPROP 2 LAST PATH I89
J 0
(-2550 3350);
DISPLAY 1.021277 (-2550 3350);
PAINT ORANGE (-2550 3350);
DISPLAY INVISIBLE (-2550 3350);
FORCEPROP 2 LAST ROOM SMB
J 0
(-2600 3350);
PAINT MONO (-2600 3350);
DISPLAY INVISIBLE (-2600 3350);
FORCEPROP 2 LAST BOM_COST SM_CONTROLLER
J 0
(-2600 3350);
PAINT MONO (-2600 3350);
DISPLAY INVISIBLE (-2600 3350);
FORCEPROP 2 LAST CDS_LIB mstr_standard
J 0
(-2350 3300);
PAINT ORANGE (-2350 3300);
DISPLAY INVISIBLE (-2350 3300);
FORCEPROP 1 LAST OFFPAGE TRUE
J 0
(-2025 3175);
PAINT GREEN (-2025 3175);
DISPLAY INVISIBLE (-2025 3175);
FORCEPROP 1 LAST COMMENT_BODY TRUE
J 0
(-2225 3200);
DISPLAY 0.872340 (-2225 3200);
PAINT GREEN (-2225 3200);
DISPLAY INVISIBLE (-2225 3200);
FORCEADD RES..1
(1600 4350);
FORCEPROP 1 LAST LOCATION R4T9
J 0
(1475 4450);
DISPLAY 0.617021 (1475 4450);
PAINT AQUA (1475 4450);
FORCEPROP 1 LAST VALUE 20.0
J 2
(1750 4450);
DISPLAY 0.617021 (1750 4450);
PAINT SKYBLUE (1750 4450);
FORCEPROP 1 LAST WATTAGE 1/16W
J 2
(2000 4450);
DISPLAY 0.617021 (2000 4450);
PAINT SKYBLUE (2000 4450);
FORCEPROP 1 LAST PART_NUMBER G21796-173
J 0
(1850 4500);
DISPLAY 0.617021 (1850 4500);
PAINT BLUE (1850 4500);
FORCEPROP 1 LAST MATERIAL CHIP
J 0
(2075 4450);
DISPLAY 0.617021 (2075 4450);
PAINT SKYBLUE (2075 4450);
FORCEPROP 1 LAST PACK_TYPE 0402
J 0
(1650 4400);
DISPLAY 0.617021 (1650 4400);
PAINT SKYBLUE (1650 4400);
FORCEPROP 1 LAST TOLERANCE 1%
J 0
(1875 4400);
DISPLAY 0.617021 (1875 4400);
PAINT SKYBLUE (1875 4400);
FORCEPROP 1 LASTPIN (1700 4350) $PN 2
J 0
(1662 4362);
DISPLAY 0.617021 (1662 4362);
PAINT MONO (1662 4362);
FORCEPROP 1 LASTPIN (1500 4350) $PN 1
J 0
(1512 4362);
DISPLAY 0.617021 (1512 4362);
PAINT MONO (1512 4362);
FORCEPROP 2 LAST ROOM MEM
J 0
(1800 4450);
DISPLAY 1.404255 (1800 4450);
PAINT ORANGE (1800 4450);
DISPLAY INVISIBLE (1800 4450);
FORCEPROP 1 LAST PATH I9
J 0
(1550 4500);
DISPLAY 0.978723 (1550 4500);
PAINT WHITE (1550 4500);
DISPLAY INVISIBLE (1550 4500);
FORCEPROP 2 LAST CDS_LOCATION R4T9
J 0
(1550 4425);
DISPLAY 0.617021 (1550 4425);
PAINT AQUA (1550 4425);
DISPLAY INVISIBLE (1550 4425);
FORCEPROP 2 LAST $SEC 1
J 0
(1550 4550);
DISPLAY 0.936170 (1550 4550);
PAINT MONO (1550 4550);
DISPLAY INVISIBLE (1550 4550);
FORCEPROP 2 LAST CDS_SEC 1
J 0
(1550 4550);
DISPLAY 1.404255 (1550 4550);
PAINT ORANGE (1550 4550);
DISPLAY INVISIBLE (1550 4550);
FORCEPROP 2 LAST CDS_LIB mstr_discrete
J 0
(1600 4350);
PAINT ORANGE (1600 4350);
DISPLAY INVISIBLE (1600 4350);
FORCEADD RES..1
(-1475 2150);
FORCEPROP 1 LAST MATERIAL CHIP
J 0
(-1900 2200);
DISPLAY 0.617021 (-1900 2200);
PAINT SKYBLUE (-1900 2200);
FORCEPROP 1 LAST PART_NUMBER G21796-066
J 0
(-1750 2200);
DISPLAY 0.617021 (-1750 2200);
PAINT BLUE (-1750 2200);
FORCEPROP 1 LASTPIN (-1575 2150) $PN 1
J 0
(-1563 2162);
DISPLAY 0.617021 (-1563 2162);
PAINT MONO (-1563 2162);
FORCEPROP 1 LAST PACK_TYPE 0402
J 0
(-1450 2200);
DISPLAY 0.617021 (-1450 2200);
PAINT SKYBLUE (-1450 2200);
FORCEPROP 1 LASTPIN (-1375 2150) $PN 2
J 0
(-1413 2162);
DISPLAY 0.617021 (-1413 2162);
PAINT MONO (-1413 2162);
FORCEPROP 1 LAST VALUE 10.0
J 2
(-1625 2275);
DISPLAY 0.617021 (-1625 2275);
PAINT SKYBLUE (-1625 2275);
FORCEPROP 1 LAST WATTAGE 1/16W
J 2
(-1350 2275);
DISPLAY 0.617021 (-1350 2275);
PAINT SKYBLUE (-1350 2275);
FORCEPROP 1 LAST TOLERANCE 1%
J 0
(-1575 2275);
DISPLAY 0.617021 (-1575 2275);
PAINT SKYBLUE (-1575 2275);
FORCEPROP 1 LAST LOCATION R6T3
J 0
(-1875 2275);
DISPLAY 0.617021 (-1875 2275);
PAINT AQUA (-1875 2275);
FORCEPROP 2 LAST CDS_LIB mstr_discrete
J 0
(-1475 2150);
PAINT MONO (-1475 2150);
DISPLAY INVISIBLE (-1475 2150);
FORCEPROP 2 LAST BOM_COST SM_CONTROLLER
J 0
(-1525 2250);
PAINT MONO (-1525 2250);
DISPLAY INVISIBLE (-1525 2250);
FORCEPROP 2 LAST CDS_SEC 1
J 0
(-1525 2350);
DISPLAY 1.404255 (-1525 2350);
PAINT ORANGE (-1525 2350);
DISPLAY INVISIBLE (-1525 2350);
FORCEPROP 2 LAST $SEC 1
J 0
(-1525 2350);
DISPLAY 0.936170 (-1525 2350);
PAINT MONO (-1525 2350);
DISPLAY INVISIBLE (-1525 2350);
FORCEPROP 2 LAST CDS_LOCATION R6T3
J 0
(-1525 2200);
DISPLAY 0.617021 (-1525 2200);
PAINT AQUA (-1525 2200);
DISPLAY INVISIBLE (-1525 2200);
FORCEPROP 1 LAST PATH I92
J 0
(-1525 2300);
DISPLAY 0.978723 (-1525 2300);
PAINT WHITE (-1525 2300);
DISPLAY INVISIBLE (-1525 2300);
FORCEPROP 2 LAST ROOM MEM
J 0
(-1525 2250);
PAINT MONO (-1525 2250);
DISPLAY INVISIBLE (-1525 2250);
FORCEADD OFFPAGE..6
(-2350 3250);
FORCEPROP 2 LASTPIN (-2300 3250) SIG_NAME SMB_DDR_DEF_SDA_G_R
J 0
(-2235 3260);
DISPLAY 0.617021 (-2235 3260);
PAINT ORANGE (-2235 3260);
FORCEPROP 2 LAST $XR0 21 
J 0
(-2629 3250);
DISPLAY 0.638298 (-2629 3250);
PAINT MONO (-2629 3250);
FORCEPROP 2 LAST PATH I93
J 0
(-2625 3300);
DISPLAY 1.021277 (-2625 3300);
PAINT ORANGE (-2625 3300);
DISPLAY INVISIBLE (-2625 3300);
FORCEPROP 2 LAST CDS_LIB mstr_standard
J 0
(-2350 3250);
PAINT MONO (-2350 3250);
DISPLAY INVISIBLE (-2350 3250);
FORCEPROP 2 LAST BOM_COST SM_CONTROLLER
J 0
(-2575 3300);
DISPLAY 1.617021 (-2575 3300);
PAINT ORANGE (-2575 3300);
DISPLAY INVISIBLE (-2575 3300);
FORCEPROP 1 LAST OFFPAGE TRUE
J 0
(-2025 3125);
PAINT GREEN (-2025 3125);
DISPLAY INVISIBLE (-2025 3125);
FORCEPROP 1 LAST COMMENT_BODY TRUE
J 0
(-2250 3175);
DISPLAY 1.872340 (-2250 3175);
PAINT GREEN (-2250 3175);
DISPLAY INVISIBLE (-2250 3175);
FORCEADD OFFPAGE..6
(-2375 2100);
FORCEPROP 2 LAST $XR0 55 
J 0
(-2624 2100);
DISPLAY 0.638298 (-2624 2100);
PAINT MONO (-2624 2100);
FORCEPROP 2 LAST PATH I94
J 0
(-2600 2150);
DISPLAY 1.021277 (-2600 2150);
PAINT ORANGE (-2600 2150);
DISPLAY INVISIBLE (-2600 2150);
FORCEPROP 2 LAST CDS_LIB mstr_standard
J 0
(-2375 2100);
PAINT MONO (-2375 2100);
DISPLAY INVISIBLE (-2375 2100);
FORCEPROP 2 LAST BOM_COST SM_CONTROLLER
J 0
(-2600 2150);
DISPLAY 1.617021 (-2600 2150);
PAINT ORANGE (-2600 2150);
DISPLAY INVISIBLE (-2600 2150);
FORCEPROP 1 LAST OFFPAGE TRUE
J 0
(-2050 1975);
PAINT GREEN (-2050 1975);
DISPLAY INVISIBLE (-2050 1975);
FORCEPROP 1 LAST COMMENT_BODY TRUE
J 0
(-2275 2025);
DISPLAY 1.872340 (-2275 2025);
PAINT GREEN (-2275 2025);
DISPLAY INVISIBLE (-2275 2025);
FORCEADD OFFPAGE..1
(-2375 2150);
FORCEPROP 2 LAST $XR0 55 
J 0
(-2596 2150);
DISPLAY 0.638298 (-2596 2150);
PAINT MONO (-2596 2150);
FORCEPROP 2 LAST PATH I95
J 0
(-2575 2200);
DISPLAY 1.021277 (-2575 2200);
PAINT ORANGE (-2575 2200);
DISPLAY INVISIBLE (-2575 2200);
FORCEPROP 2 LAST ROOM SMB
J 0
(-2625 2200);
PAINT MONO (-2625 2200);
DISPLAY INVISIBLE (-2625 2200);
FORCEPROP 2 LAST CDS_LIB mstr_standard
J 0
(-2375 2150);
PAINT ORANGE (-2375 2150);
DISPLAY INVISIBLE (-2375 2150);
FORCEPROP 2 LAST BOM_COST SM_CONTROLLER
J 0
(-2625 2200);
PAINT MONO (-2625 2200);
DISPLAY INVISIBLE (-2625 2200);
FORCEPROP 1 LAST OFFPAGE TRUE
J 0
(-2050 2025);
PAINT GREEN (-2050 2025);
DISPLAY INVISIBLE (-2050 2025);
FORCEPROP 1 LAST COMMENT_BODY TRUE
J 0
(-2250 2050);
DISPLAY 0.872340 (-2250 2050);
PAINT GREEN (-2250 2050);
DISPLAY INVISIBLE (-2250 2050);
FORCEADD RES..1
(-1575 950);
FORCEPROP 1 LASTPIN (-1475 950) $PN 2
J 0
(-1513 962);
DISPLAY 0.617021 (-1513 962);
PAINT MONO (-1513 962);
FORCEPROP 1 LAST LOCATION R7M3
J 0
(-2000 1075);
DISPLAY 0.617021 (-2000 1075);
PAINT AQUA (-2000 1075);
FORCEPROP 1 LAST TOLERANCE 1%
J 0
(-1650 1075);
DISPLAY 0.617021 (-1650 1075);
PAINT SKYBLUE (-1650 1075);
FORCEPROP 1 LAST WATTAGE 1/16W
J 2
(-1400 1075);
DISPLAY 0.617021 (-1400 1075);
PAINT SKYBLUE (-1400 1075);
FORCEPROP 1 LAST VALUE 10.0
J 2
(-1725 1075);
DISPLAY 0.617021 (-1725 1075);
PAINT SKYBLUE (-1725 1075);
FORCEPROP 1 LAST PACK_TYPE 0402
J 0
(-1550 1025);
DISPLAY 0.617021 (-1550 1025);
PAINT SKYBLUE (-1550 1025);
FORCEPROP 1 LASTPIN (-1675 950) $PN 1
J 0
(-1663 962);
DISPLAY 0.617021 (-1663 962);
PAINT MONO (-1663 962);
FORCEPROP 1 LAST PART_NUMBER G21796-066
J 0
(-1850 1025);
DISPLAY 0.617021 (-1850 1025);
PAINT BLUE (-1850 1025);
FORCEPROP 1 LAST MATERIAL CHIP
J 0
(-2000 1025);
DISPLAY 0.617021 (-2000 1025);
PAINT SKYBLUE (-2000 1025);
FORCEPROP 2 LAST ROOM MEM
J 0
(-1625 1050);
PAINT MONO (-1625 1050);
DISPLAY INVISIBLE (-1625 1050);
FORCEPROP 1 LAST PATH I98
J 0
(-1625 1100);
DISPLAY 0.978723 (-1625 1100);
PAINT WHITE (-1625 1100);
DISPLAY INVISIBLE (-1625 1100);
FORCEPROP 2 LAST CDS_LOCATION R7M3
J 0
(-1625 1000);
DISPLAY 0.617021 (-1625 1000);
PAINT AQUA (-1625 1000);
DISPLAY INVISIBLE (-1625 1000);
FORCEPROP 2 LAST $SEC 1
J 0
(-1625 1150);
DISPLAY 0.936170 (-1625 1150);
PAINT MONO (-1625 1150);
DISPLAY INVISIBLE (-1625 1150);
FORCEPROP 2 LAST CDS_SEC 1
J 0
(-1625 1150);
DISPLAY 1.404255 (-1625 1150);
PAINT ORANGE (-1625 1150);
DISPLAY INVISIBLE (-1625 1150);
FORCEPROP 2 LAST CDS_LIB mstr_discrete
J 0
(-1575 950);
PAINT MONO (-1575 950);
DISPLAY INVISIBLE (-1575 950);
FORCEPROP 2 LAST BOM_COST SM_CONTROLLER
J 0
(-1625 1050);
PAINT MONO (-1625 1050);
DISPLAY INVISIBLE (-1625 1050);
FORCEADD OFFPAGE..1
(-2400 950);
FORCEPROP 2 LAST $XR0 55 
J 0
(-2651 950);
DISPLAY 0.638298 (-2651 950);
PAINT MONO (-2651 950);
FORCEPROP 2 LAST PATH I99
J 0
(-2650 1000);
DISPLAY 1.021277 (-2650 1000);
PAINT ORANGE (-2650 1000);
DISPLAY INVISIBLE (-2650 1000);
FORCEPROP 2 LAST ROOM SMB
J 0
(-2650 1000);
PAINT MONO (-2650 1000);
DISPLAY INVISIBLE (-2650 1000);
FORCEPROP 2 LAST CDS_LIB mstr_standard
J 0
(-2400 950);
PAINT ORANGE (-2400 950);
DISPLAY INVISIBLE (-2400 950);
FORCEPROP 2 LAST BOM_COST SM_CONTROLLER
J 0
(-2650 1000);
PAINT MONO (-2650 1000);
DISPLAY INVISIBLE (-2650 1000);
FORCEPROP 1 LAST OFFPAGE TRUE
J 0
(-2075 825);
PAINT GREEN (-2075 825);
DISPLAY INVISIBLE (-2075 825);
FORCEPROP 1 LAST COMMENT_BODY TRUE
J 0
(-2275 850);
DISPLAY 0.872340 (-2275 850);
PAINT GREEN (-2275 850);
DISPLAY INVISIBLE (-2275 850);
FORCEADD INTEL_CORP_BPAGE..1
(4250 200);
FORCEPROP 1 LAST CDS_CON_LAST_MODIFIED Fri Jun 16 17:48:40 2017
J 0
(2825 525);
PAINT ORANGE (2825 525);
DISPLAY INVISIBLE (2825 525);
FORCEPROP 1 LAST CUSTOM_TXT_CDS <CURRENT_DESIGN_SHEET> OF <TOTAL_DESIGN_SHEETS>
J 0
(3750 225);
PAINT ORANGE (3750 225);
FORCEPROP 1 LAST CUSTOM_TXT_CDS <CON_LAST_MODIFIED>
J 0
(250 300);
PAINT ORANGE (250 300);
FORCEPROP 2 LAST CUSTOM_TXT_CDS <XR_PAGE_TITLE>
J 0
(-3640 5450);
DISPLAY 0.638298 (-3640 5450);
PAINT PINK (-3640 5450);
DISPLAY INVISIBLE (-3640 5450);
FORCEPROP 1 LAST SCH_TITLE CPU SIDE BAND:DIMM SMBUS TRANSLATORS
J 0
(-3700 250);
DISPLAY 1.212766 (-3700 250);
PAINT ORANGE (-3700 250);
FORCEPROP 2 LAST PAGE_BORDER TRUE
J 0
(-3640 5450);
DISPLAY 0.638298 (-3640 5450);
PAINT PINK (-3640 5450);
DISPLAY INVISIBLE (-3640 5450);
FORCEPROP 2 LAST CDS_LIB mstr_symbols
J 0
(4250 200);
PAINT MONO (4250 200);
DISPLAY INVISIBLE (4250 200);
FORCEPROP 1 LAST COMMENT_BODY TRUE
J 0
(4262 212);
DISPLAY 0.468085 (4262 212);
PAINT GREEN (4262 212);
DISPLAY INVISIBLE (4262 212);
FORCEPROP 2 LAST CDS_XR_PAGE_TITLE CR-99 : @BASEBOARD_FAB2_LIB.BASEBOARD_FAB2(SCH_1):PAGE99
J 0
(-3640 5450);
DISPLAY 0.638298 (-3640 5450);
PAINT PINK (-3640 5450);
DISPLAY INVISIBLE (-3640 5450);
WIRE 16 -1 (1900 5025)(1900 5050);
WIRE 16 -1 (925 3825)(925 3850);
WIRE 16 -1 (1275 3825)(925 3825);
WIRE 16 -1 (925 3700)(925 3825);
WIRE 16 -1 (1275 3700)(1275 3825);
WIRE 16 -1 (875 2675)(875 2700);
WIRE 16 -1 (1225 2675)(875 2675);
WIRE 16 -1 (875 2550)(875 2675);
WIRE 16 -1 (1225 2550)(1225 2675);
WIRE 16 -1 (875 1475)(875 1500);
WIRE 16 -1 (1225 1475)(875 1475);
WIRE 16 -1 (875 1350)(875 1475);
WIRE 16 -1 (1225 1350)(1225 1475);
WIRE 16 -1 (1475 5000)(1475 5050);
WIRE 16 -1 (650 4450)(650 4575);
WIRE 16 -1 (550 4450)(650 4450);
WIRE 16 -1 (875 4875)(875 4900);
WIRE 16 -1 (1225 4875)(875 4875);
WIRE 16 -1 (875 4750)(875 4875);
WIRE 16 -1 (1225 4750)(1225 4875);
WIRE 16 -1 (-475 4450)(-475 4825);
WIRE 16 -1 (-250 4450)(-475 4450);
WIRE 16 -1 (-900 4875)(-900 4925);
WIRE 16 -1 (-650 4875)(-900 4875);
WIRE 16 -1 (-900 4875)(-1025 4875);
WIRE 16 -1 (-1025 4750)(-1025 4875);
WIRE 16 -1 (-650 4750)(-650 4875);
WIRE 16 -1 (2125 3875)(2125 3900);
WIRE 16 -1 (2125 3675)(2125 3575);
WIRE 16 -1 (2225 2800)(2225 2825);
WIRE 16 -1 (2225 2600)(2225 2500);
WIRE 16 -1 (1900 4825)(1900 4725);
WIRE 16 -1 (1625 3850)(1625 3900);
WIRE 16 -1 (1625 3650)(1625 3550);
WIRE 16 -1 (1650 2775)(1650 2825);
WIRE 16 -1 (1650 2575)(1650 2475);
WIRE 16 -1 (2250 1625)(2250 1650);
WIRE 16 -1 (2250 1425)(2250 1325);
WIRE 16 -1 (1675 1600)(1675 1650);
WIRE 16 -1 (1675 1400)(1675 1300);
WIRE 16 -1 (625 3400)(625 3525);
WIRE 16 -1 (550 3400)(625 3400);
WIRE 16 -1 (600 2250)(600 2375);
WIRE 16 -1 (550 2250)(600 2250);
WIRE 16 -1 (-500 3400)(-500 3775);
WIRE 16 -1 (-250 3400)(-500 3400);
WIRE 16 -1 (-925 3825)(-925 3875);
WIRE 16 -1 (-675 3825)(-925 3825);
WIRE 16 -1 (-925 3825)(-1050 3825);
WIRE 16 -1 (-1050 3700)(-1050 3825);
WIRE 16 -1 (-675 3700)(-675 3825);
WIRE 16 -1 (-525 2250)(-525 2625);
WIRE 16 -1 (-250 2250)(-525 2250);
WIRE 16 -1 (-950 2675)(-950 2725);
WIRE 16 -1 (-700 2675)(-950 2675);
WIRE 16 -1 (-950 2675)(-1075 2675);
WIRE 16 -1 (-1075 2550)(-1075 2675);
WIRE 16 -1 (-700 2550)(-700 2675);
WIRE 16 -1 (575 1050)(575 1175);
WIRE 16 -1 (550 1050)(575 1050);
WIRE 16 -1 (-550 1050)(-550 1425);
WIRE 16 -1 (-250 1050)(-550 1050);
WIRE 16 -1 (-975 1475)(-975 1525);
WIRE 16 -1 (-725 1475)(-975 1475);
WIRE 16 -1 (-975 1475)(-1100 1475);
WIRE 16 -1 (-1100 1350)(-1100 1475);
WIRE 16 -1 (-725 1350)(-725 1475);
WIRE 16 -1 (1475 4800)(1475 4700);
WIRE 16 -1 (-1025 4550)(-1025 4350);
WIRE 16 -1 (-1025 4350)(-250 4350);
FORCEPROP 2 LAST SIG_NAME SMB_DDR_ABC_SCL_G
J 2
(-360 4360);
DISPLAY 0.617021 (-360 4360);
PAINT ORANGE (-360 4360);
FORCEPROP 2 LASTPROP $XRERR UNIQUE?
J 0
(-600 4360);
DISPLAY 0.638298 (-600 4360);
PAINT MONO (-600 4360);
DISPLAY INVISIBLE (-600 4360);
WIRE 16 -1 (-1400 4350)(-1025 4350);
WIRE 16 -1 (1700 2100)(2575 2100);
FORCEPROP 2 LAST SIG_NAME SMB_DDR_GHJ_VPP_SDA
J 0
(1915 2110);
DISPLAY 0.617021 (1915 2110);
PAINT ORANGE (1915 2110);
WIRE 16 -1 (875 2150)(550 2150);
FORCEPROP 2 LAST SIG_NAME SMB_DDR_GHJ_VPP_SCL_R
J 0
(665 2160);
DISPLAY 0.617021 (665 2160);
PAINT ORANGE (665 2160);
FORCEPROP 2 LASTPROP $XRERR UNIQUE?
J 0
(425 2160);
DISPLAY 0.638298 (425 2160);
PAINT MONO (425 2160);
DISPLAY INVISIBLE (425 2160);
WIRE 16 -1 (875 2350)(875 2150);
WIRE 16 -1 (875 2150)(1500 2150);
WIRE 16 -1 (550 2100)(1225 2100);
FORCEPROP 2 LAST SIG_NAME SMB_DDR_GHJ_VPP_SDA_R
J 0
(665 2110);
DISPLAY 0.617021 (665 2110);
PAINT ORANGE (665 2110);
FORCEPROP 2 LASTPROP $XRERR UNIQUE?
J 0
(425 2110);
DISPLAY 0.638298 (425 2110);
PAINT MONO (425 2110);
DISPLAY INVISIBLE (425 2110);
WIRE 16 -1 (1225 2100)(1500 2100);
WIRE 16 -1 (1225 2350)(1225 2100);
WIRE 16 -1 (-2350 900)(-1300 900);
FORCEPROP 2 LAST SIG_NAME SMB_DDR_KLM_SDA_G_R
J 0
(-2325 910);
DISPLAY 0.617021 (-2325 910);
PAINT ORANGE (-2325 910);
WIRE 16 -1 (-1475 950)(-1100 950);
WIRE 16 -1 (-1100 950)(-250 950);
FORCEPROP 2 LAST SIG_NAME SMB_DDR_KLM_SCL_G
J 2
(-360 960);
DISPLAY 0.617021 (-360 960);
PAINT ORANGE (-360 960);
FORCEPROP 2 LASTPROP $XRERR UNIQUE?
J 0
(-600 960);
DISPLAY 0.638298 (-600 960);
PAINT MONO (-600 960);
DISPLAY INVISIBLE (-600 960);
WIRE 16 -1 (-1100 1150)(-1100 950);
WIRE 16 -1 (-725 900)(-1100 900);
WIRE 16 -1 (-725 900)(-250 900);
FORCEPROP 2 LAST SIG_NAME SMB_DDR_KLM_SDA_G
J 2
(-360 910);
DISPLAY 0.617021 (-360 910);
PAINT ORANGE (-360 910);
FORCEPROP 2 LASTPROP $XRERR UNIQUE?
J 0
(-600 910);
DISPLAY 0.638298 (-600 910);
PAINT MONO (-600 910);
DISPLAY INVISIBLE (-600 910);
WIRE 16 -1 (-725 1150)(-725 900);
WIRE 16 -1 (-1450 800)(-250 800);
FORCEPROP 2 LAST SIG_NAME TP_SMB_DDR_KLM_EN
J 0
(-1185 810);
DISPLAY 0.617021 (-1185 810);
PAINT ORANGE (-1185 810);
FORCEPROP 2 LASTPROP $XRERR UNIQUE?
J 0
(-1690 800);
DISPLAY 0.638298 (-1690 800);
PAINT MONO (-1690 800);
DISPLAY INVISIBLE (-1690 800);
WIRE 16 -1 (-2350 950)(-1675 950);
FORCEPROP 2 LAST SIG_NAME SMB_DDR_KLM_SCL_G_R
J 0
(-2325 960);
DISPLAY 0.617021 (-2325 960);
PAINT ORANGE (-2325 960);
WIRE 16 -1 (1700 900)(2575 900);
FORCEPROP 2 LAST SIG_NAME SMB_DDR_KLM_VPP_SDA
J 0
(1915 910);
DISPLAY 0.617021 (1915 910);
PAINT ORANGE (1915 910);
WIRE 16 -1 (1700 950)(2575 950);
FORCEPROP 2 LAST SIG_NAME SMB_DDR_KLM_VPP_SCL
J 0
(1915 960);
DISPLAY 0.617021 (1915 960);
PAINT ORANGE (1915 960);
WIRE 16 -1 (-1425 2000)(-250 2000);
FORCEPROP 2 LAST SIG_NAME TP_SMB_DDR_GHJ_EN
J 0
(-1210 2010);
DISPLAY 0.617021 (-1210 2010);
PAINT ORANGE (-1210 2010);
FORCEPROP 2 LASTPROP $XRERR UNIQUE?
J 0
(-1665 2000);
DISPLAY 0.638298 (-1665 2000);
PAINT MONO (-1665 2000);
DISPLAY INVISIBLE (-1665 2000);
WIRE 16 -1 (-1375 2150)(-1075 2150);
WIRE 16 -1 (-1075 2150)(-250 2150);
FORCEPROP 2 LAST SIG_NAME SMB_DDR_GHJ_SCL_G
J 2
(-360 2160);
DISPLAY 0.617021 (-360 2160);
PAINT ORANGE (-360 2160);
FORCEPROP 2 LASTPROP $XRERR UNIQUE?
J 0
(-600 2160);
DISPLAY 0.638298 (-600 2160);
PAINT MONO (-600 2160);
DISPLAY INVISIBLE (-600 2160);
WIRE 16 -1 (-1075 2350)(-1075 2150);
WIRE 16 -1 (-700 2350)(-700 2100);
WIRE 16 -1 (-700 2100)(-250 2100);
WIRE 16 -1 (-1000 2100)(-700 2100);
FORCEPROP 2 LAST SIG_NAME SMB_DDR_GHJ_SDA_G
J 2
(-360 2110);
DISPLAY 0.617021 (-360 2110);
PAINT ORANGE (-360 2110);
FORCEPROP 2 LASTPROP $XRERR UNIQUE?
J 0
(-600 2110);
DISPLAY 0.638298 (-600 2110);
PAINT MONO (-600 2110);
DISPLAY INVISIBLE (-600 2110);
WIRE 16 -1 (-2325 2100)(-1200 2100);
FORCEPROP 2 LAST SIG_NAME SMB_DDR_GHJ_SDA_G_R
J 0
(-2250 2110);
DISPLAY 0.617021 (-2250 2110);
PAINT ORANGE (-2250 2110);
WIRE 16 -1 (-2325 2150)(-1575 2150);
FORCEPROP 2 LAST SIG_NAME SMB_DDR_GHJ_SCL_G_R
J 0
(-2250 2160);
DISPLAY 0.617021 (-2250 2160);
PAINT ORANGE (-2250 2160);
WIRE 16 -1 (-2300 3250)(-1275 3250);
WIRE 16 -1 (-1400 3150)(-250 3150);
FORCEPROP 2 LAST SIG_NAME TP_SMB_DDR_DEF_EN
J 0
(-1160 3160);
DISPLAY 0.617021 (-1160 3160);
PAINT ORANGE (-1160 3160);
FORCEPROP 2 LASTPROP $XRERR UNIQUE?
J 0
(-1640 3150);
DISPLAY 0.638298 (-1640 3150);
PAINT MONO (-1640 3150);
DISPLAY INVISIBLE (-1640 3150);
WIRE 16 -1 (-1475 3300)(-1050 3300);
WIRE 16 -1 (-1050 3300)(-250 3300);
FORCEPROP 2 LAST SIG_NAME SMB_DDR_DEF_SCL_G
J 2
(-360 3310);
DISPLAY 0.617021 (-360 3310);
PAINT ORANGE (-360 3310);
FORCEPROP 2 LASTPROP $XRERR UNIQUE?
J 0
(-600 3310);
DISPLAY 0.638298 (-600 3310);
PAINT MONO (-600 3310);
DISPLAY INVISIBLE (-600 3310);
WIRE 16 -1 (-1050 3500)(-1050 3300);
WIRE 16 -1 (-675 3500)(-675 3250);
WIRE 16 -1 (-675 3250)(-250 3250);
WIRE 16 -1 (-1075 3250)(-675 3250);
FORCEPROP 2 LAST SIG_NAME SMB_DDR_DEF_SDA_G
J 2
(-360 3260);
DISPLAY 0.617021 (-360 3260);
PAINT ORANGE (-360 3260);
FORCEPROP 2 LASTPROP $XRERR UNIQUE?
J 0
(-600 3260);
DISPLAY 0.638298 (-600 3260);
PAINT MONO (-600 3260);
DISPLAY INVISIBLE (-600 3260);
WIRE 16 -1 (-1375 4200)(-250 4200);
FORCEPROP 2 LAST SIG_NAME TP_SMB_DDR_ABC_EN
J 0
(-1185 4210);
DISPLAY 0.617021 (-1185 4210);
PAINT ORANGE (-1185 4210);
FORCEPROP 2 LASTPROP $XRERR UNIQUE?
J 0
(-1615 4200);
DISPLAY 0.638298 (-1615 4200);
PAINT MONO (-1615 4200);
DISPLAY INVISIBLE (-1615 4200);
WIRE 16 -1 (-650 4550)(-650 4300);
WIRE 16 -1 (-650 4300)(-250 4300);
WIRE 16 -1 (-975 4300)(-650 4300);
FORCEPROP 2 LAST SIG_NAME SMB_DDR_ABC_SDA_G
J 2
(-360 4310);
DISPLAY 0.617021 (-360 4310);
PAINT ORANGE (-360 4310);
FORCEPROP 2 LASTPROP $XRERR UNIQUE?
J 0
(-600 4310);
DISPLAY 0.638298 (-600 4310);
PAINT MONO (-600 4310);
DISPLAY INVISIBLE (-600 4310);
WIRE 16 -1 (-2275 4300)(-1175 4300);
WIRE 16 -1 (-2275 4350)(-1600 4350);
FORCEPROP 2 LAST SIG_NAME SMB_DDR_ABC_SCL_G_R
J 0
(-2210 4360);
DISPLAY 0.617021 (-2210 4360);
PAINT ORANGE (-2210 4360);
WIRE 16 -1 (875 4550)(875 4350);
WIRE 16 -1 (875 4350)(1500 4350);
WIRE 16 -1 (550 4350)(875 4350);
FORCEPROP 2 LAST SIG_NAME SMB_DDR_ABC_VPP_SCL_R
J 0
(640 4360);
DISPLAY 0.617021 (640 4360);
PAINT ORANGE (640 4360);
FORCEPROP 2 LASTPROP $XRERR UNIQUE?
J 0
(400 4360);
DISPLAY 0.638298 (400 4360);
PAINT MONO (400 4360);
DISPLAY INVISIBLE (400 4360);
WIRE 16 -1 (1225 4550)(1225 4300);
WIRE 16 -1 (1225 4300)(1500 4300);
WIRE 16 -1 (550 4300)(1225 4300);
FORCEPROP 2 LAST SIG_NAME SMB_DDR_ABC_VPP_SDA_R
J 0
(640 4310);
DISPLAY 0.617021 (640 4310);
PAINT ORANGE (640 4310);
FORCEPROP 2 LASTPROP $XRERR UNIQUE?
J 0
(400 4310);
DISPLAY 0.638298 (400 4310);
PAINT MONO (400 4310);
DISPLAY INVISIBLE (400 4310);
WIRE 16 -1 (1700 4350)(2550 4350);
FORCEPROP 2 LAST SIG_NAME SMB_DDR_ABC_VPP_SCL
J 0
(1890 4360);
DISPLAY 0.617021 (1890 4360);
PAINT ORANGE (1890 4360);
WIRE 16 -1 (1700 4300)(2550 4300);
WIRE 16 -1 (925 3300)(550 3300);
FORCEPROP 2 LAST SIG_NAME SMB_DDR_DEF_VPP_SCL_R
J 0
(640 3310);
DISPLAY 0.617021 (640 3310);
PAINT ORANGE (640 3310);
FORCEPROP 2 LASTPROP $XRERR UNIQUE?
J 0
(400 3310);
DISPLAY 0.638298 (400 3310);
PAINT MONO (400 3310);
DISPLAY INVISIBLE (400 3310);
WIRE 16 -1 (925 3500)(925 3300);
WIRE 16 -1 (925 3300)(1500 3300);
WIRE 16 -1 (1700 3250)(2550 3250);
WIRE 16 -1 (1700 3300)(2550 3300);
FORCEPROP 2 LAST SIG_NAME SMB_DDR_DEF_VPP_SCL
J 0
(1890 3310);
DISPLAY 0.617021 (1890 3310);
PAINT ORANGE (1890 3310);
WIRE 16 -1 (1275 3500)(1275 3250);
WIRE 16 -1 (1275 3250)(1500 3250);
WIRE 16 -1 (550 3250)(1275 3250);
FORCEPROP 2 LAST SIG_NAME SMB_DDR_DEF_VPP_SDA_R
J 0
(640 3260);
DISPLAY 0.617021 (640 3260);
PAINT ORANGE (640 3260);
FORCEPROP 2 LASTPROP $XRERR UNIQUE?
J 0
(400 3260);
DISPLAY 0.638298 (400 3260);
PAINT MONO (400 3260);
DISPLAY INVISIBLE (400 3260);
WIRE 16 -1 (1225 900)(1500 900);
WIRE 16 -1 (1225 1150)(1225 900);
WIRE 16 -1 (550 900)(1225 900);
FORCEPROP 2 LAST SIG_NAME SMB_DDR_KLM_VPP_SDA_R
J 0
(690 910);
DISPLAY 0.617021 (690 910);
PAINT ORANGE (690 910);
FORCEPROP 2 LASTPROP $XRERR UNIQUE?
J 0
(450 910);
DISPLAY 0.638298 (450 910);
PAINT MONO (450 910);
DISPLAY INVISIBLE (450 910);
WIRE 16 -1 (875 950)(550 950);
FORCEPROP 2 LAST SIG_NAME SMB_DDR_KLM_VPP_SCL_R
J 0
(690 960);
DISPLAY 0.617021 (690 960);
PAINT ORANGE (690 960);
FORCEPROP 2 LASTPROP $XRERR UNIQUE?
J 0
(450 960);
DISPLAY 0.638298 (450 960);
PAINT MONO (450 960);
DISPLAY INVISIBLE (450 960);
WIRE 16 -1 (875 950)(875 1150);
WIRE 16 -1 (875 950)(1500 950);
WIRE 16 -1 (-2300 3300)(-1675 3300);
FORCEPROP 2 LAST SIG_NAME SMB_DDR_DEF_SCL_G_R
J 0
(-2235 3310);
DISPLAY 0.617021 (-2235 3310);
PAINT ORANGE (-2235 3310);
WIRE 16 -1 (1700 2150)(2575 2150);
FORCEPROP 2 LAST SIG_NAME SMB_DDR_GHJ_VPP_SCL
J 0
(1915 2160);
DISPLAY 0.617021 (1915 2160);
PAINT ORANGE (1915 2160);
DOT 1 (-950 2675);
DOT 1 (-1050 3300);
DOT 1 (-1025 4350);
DOT 1 (-650 4300);
DOT 1 (-1075 2150);
DOT 1 (1225 4300);
DOT 1 (875 950);
DOT 1 (875 4875);
DOT 1 (875 4350);
DOT 1 (-675 3250);
DOT 1 (875 2150);
DOT 1 (-700 2100);
DOT 1 (-975 1475);
DOT 1 (-725 900);
DOT 1 (-1100 950);
DOT 1 (1275 3250);
DOT 1 (925 3825);
DOT 1 (875 2675);
DOT 1 (1225 900);
DOT 1 (875 1475);
DOT 1 (925 3300);
DOT 1 (-925 3825);
DOT 1 (-900 4875);
DOT 1 (1225 2100);
FORCENOTE
ROOM=MEM
(3520 675) 0;
DISPLAY LEFT (3520 675);
DISPLAY 1.595745 (3520 675);
PAINT PURPLE (3520 675);
QUIT
